FILE_TYPE = MACRO_DRAWING;
SET COLOR_WIRE YELLOW;
SET COLOR_PROP MONO;
SET COLOR_DOT WHITE;
SET COLOR_ARC YELLOW;
SET COLOR_BODY GREEN;
SET COLOR_NOTE MONO;
SET PROP_DISPLAY VALUE;
SET PAGE_NUMBER P114;
FORCEADD OFFPAGE..2
(3700 2250);
FORCEPROP 2 LAST $XR0 108 
J 0
(3889 2250);
DISPLAY 0.638298 (3889 2250);
PAINT MONO (3889 2250);
FORCEPROP 1 LAST COMMENT_BODY TRUE
J 0
(3655 2155);
DISPLAY 0.872340 (3655 2155);
PAINT PEACH (3655 2155);
DISPLAY INVISIBLE (3655 2155);
FORCEPROP 2 LAST CDS_LIB mstr_standard
J 0
(3700 2250);
PAINT ORANGE (3700 2250);
DISPLAY INVISIBLE (3700 2250);
FORCEPROP 1 LAST OFFPAGE TRUE
J 0
(4025 2125);
DISPLAY 0.872340 (4025 2125);
PAINT GREEN (4025 2125);
DISPLAY INVISIBLE (4025 2125);
FORCEPROP 2 LAST PATH I103
J 0
(3875 2325);
DISPLAY 1.021277 (3875 2325);
PAINT ORANGE (3875 2325);
DISPLAY INVISIBLE (3875 2325);
FORCEADD OFFPAGE..2
(3700 2200);
FORCEPROP 2 LAST $XR0 108 
J 0
(3889 2200);
DISPLAY 0.638298 (3889 2200);
PAINT MONO (3889 2200);
FORCEPROP 1 LAST COMMENT_BODY TRUE
J 0
(3655 2105);
DISPLAY 0.872340 (3655 2105);
PAINT PEACH (3655 2105);
DISPLAY INVISIBLE (3655 2105);
FORCEPROP 2 LAST CDS_LIB mstr_standard
J 0
(3700 2200);
PAINT ORANGE (3700 2200);
DISPLAY INVISIBLE (3700 2200);
FORCEPROP 1 LAST OFFPAGE TRUE
J 0
(4025 2075);
DISPLAY 0.872340 (4025 2075);
PAINT GREEN (4025 2075);
DISPLAY INVISIBLE (4025 2075);
FORCEPROP 2 LAST PATH I104
J 0
(3875 2275);
DISPLAY 1.021277 (3875 2275);
PAINT ORANGE (3875 2275);
DISPLAY INVISIBLE (3875 2275);
FORCEADD RES..1
(2300 1350);
FORCEPROP 1 LAST WATTAGE 1/16W
J 2
(2175 1300);
DISPLAY 0.617021 (2175 1300);
PAINT SKYBLUE (2175 1300);
FORCEPROP 1 LASTPIN (2200 1350) $PN 1
J 0
(2212 1362);
DISPLAY 0.617021 (2212 1362);
PAINT ORANGE (2212 1362);
FORCEPROP 1 LAST VALUE 10.0
J 2
(2200 1350);
DISPLAY 0.617021 (2200 1350);
PAINT SKYBLUE (2200 1350);
FORCEPROP 1 LAST TOLERANCE 1%
J 0
(2300 1300);
DISPLAY 0.617021 (2300 1300);
PAINT SKYBLUE (2300 1300);
FORCEPROP 1 LAST PART_NUMBER G21796-066
J 0
(2150 1250);
DISPLAY 0.617021 (2150 1250);
PAINT BLUE (2150 1250);
FORCEPROP 1 LAST LOCATION R8B20
J 0
(2250 1400);
DISPLAY 0.617021 (2250 1400);
PAINT AQUA (2250 1400);
FORCEPROP 1 LAST MATERIAL CHIP
J 0
(2375 1300);
DISPLAY 0.617021 (2375 1300);
PAINT SKYBLUE (2375 1300);
FORCEPROP 1 LASTPIN (2400 1350) $PN 2
J 0
(2362 1362);
DISPLAY 0.617021 (2362 1362);
PAINT ORANGE (2362 1362);
FORCEPROP 1 LAST PACK_TYPE 0402
J 0
(2500 1300);
DISPLAY 0.617021 (2500 1300);
PAINT SKYBLUE (2500 1300);
FORCEPROP 2 LAST CDS_LIB mstr_discrete
J 0
(2300 1350);
PAINT ORANGE (2300 1350);
DISPLAY INVISIBLE (2300 1350);
FORCEPROP 2 LAST CDS_LOCATION R8B20
J 0
(2250 1400);
DISPLAY 0.617021 (2250 1400);
PAINT AQUA (2250 1400);
DISPLAY INVISIBLE (2250 1400);
FORCEPROP 1 LAST PATH I110
J 0
(2250 1500);
DISPLAY 0.978723 (2250 1500);
PAINT WHITE (2250 1500);
DISPLAY INVISIBLE (2250 1500);
FORCEPROP 2 LAST ROOM SB
J 0
(2250 1500);
DISPLAY 1.021277 (2250 1500);
PAINT ORANGE (2250 1500);
DISPLAY INVISIBLE (2250 1500);
FORCEPROP 2 LAST SEC_TYPE 0402
J 0
(2250 1550);
DISPLAY 1.021277 (2250 1550);
PAINT ORANGE (2250 1550);
DISPLAY INVISIBLE (2250 1550);
FORCEPROP 2 LAST SEC 1
J 0
(2250 1550);
DISPLAY 0.680851 (2250 1550);
PAINT MONO (2250 1550);
DISPLAY INVISIBLE (2250 1550);
FORCEADD RES..2
(2900 1100);
FORCEPROP 1 LAST PART_NUMBER G21796-047
J 0
(2940 975);
DISPLAY 0.617021 (2940 975);
PAINT BLUE (2940 975);
FORCEPROP 1 LAST PACK_TYPE 0402
J 0
(2940 925);
DISPLAY 0.617021 (2940 925);
PAINT SKYBLUE (2940 925);
FORCEPROP 1 LAST MATERIAL EMPTY
J 0
(2940 1025);
DISPLAY 0.617021 (2940 1025);
PAINT RED (2940 1025);
FORCEPROP 1 LAST VALUE 49.9
J 0
(2945 1175);
DISPLAY 0.617021 (2945 1175);
PAINT SKYBLUE (2945 1175);
FORCEPROP 1 LASTPIN (2900 1000) $PN 2
J 0
(2905 1010);
DISPLAY 0.617021 (2905 1010);
PAINT ORANGE (2905 1010);
FORCEPROP 1 LASTPIN (2900 1200) $PN 1
J 0
(2905 1162);
DISPLAY 0.617021 (2905 1162);
PAINT ORANGE (2905 1162);
FORCEPROP 1 LAST TOLERANCE 1%
J 0
(2945 1125);
DISPLAY 0.617021 (2945 1125);
PAINT SKYBLUE (2945 1125);
FORCEPROP 1 LAST WATTAGE 1/16W
J 0
(2940 1075);
DISPLAY 0.617021 (2940 1075);
PAINT SKYBLUE (2940 1075);
FORCEPROP 1 LAST LOCATION R8B21
J 0
(2945 1225);
DISPLAY 0.617021 (2945 1225);
PAINT AQUA (2945 1225);
FORCEPROP 2 LAST CDS_LIB mstr_discrete
J 0
(2900 1100);
PAINT ORANGE (2900 1100);
DISPLAY INVISIBLE (2900 1100);
FORCEPROP 2 LAST CDS_LOCATION R8B21
J 0
(2945 1225);
DISPLAY 0.617021 (2945 1225);
PAINT AQUA (2945 1225);
DISPLAY INVISIBLE (2945 1225);
FORCEPROP 1 LAST PATH I124
J 0
(2950 1275);
DISPLAY 0.978723 (2950 1275);
PAINT WHITE (2950 1275);
DISPLAY INVISIBLE (2950 1275);
FORCEPROP 0 LAST ROOM SB
J 0
(2850 1300);
DISPLAY 1.021277 (2850 1300);
PAINT ORANGE (2850 1300);
DISPLAY INVISIBLE (2850 1300);
FORCEPROP 2 LAST SEC 1
J 0
(2950 1325);
DISPLAY 0.680851 (2950 1325);
PAINT MONO (2950 1325);
DISPLAY INVISIBLE (2950 1325);
FORCEPROP 2 LAST SEC_TYPE 0402
J 0
(2950 1325);
DISPLAY 1.021277 (2950 1325);
PAINT ORANGE (2950 1325);
DISPLAY INVISIBLE (2950 1325);
FORCEADD GND..1
(2900 850);
FORCEPROP 3 LASTPIN (2900 900) SIG_NAME GND\g
J 0
(2910 910);
DISPLAY 0.659574 (2910 910);
PAINT MONO (2910 910);
DISPLAY INVISIBLE (2910 910);
FORCEPROP 1 LAST BODY_TYPE PLUMBING
J 0
(2855 807);
DISPLAY 0.340426 (2855 807);
PAINT GREEN (2855 807);
DISPLAY INVISIBLE (2855 807);
FORCEPROP 2 LAST CDS_LIB mstr_symbols
J 0
(2900 850);
PAINT ORANGE (2900 850);
DISPLAY INVISIBLE (2900 850);
FORCEPROP 1 LAST VOLTAGE 0.0V
J 0
(2855 807);
DISPLAY 0.340426 (2855 807);
PAINT SKYBLUE (2855 807);
DISPLAY INVISIBLE (2855 807);
FORCEPROP 1 LAST PATH I125
J 0
(2975 850);
DISPLAY 0.872340 (2975 850);
PAINT AQUA (2975 850);
DISPLAY INVISIBLE (2975 850);
FORCEPROP 1 LAST SIZE 1B
J 0
(2975 800);
DISPLAY 0.872340 (2975 800);
PAINT AQUA (2975 800);
DISPLAY INVISIBLE (2975 800);
FORCEPROP 1 LAST HDL_POWER GND
J 0
(2900 1000);
DISPLAY 0.872340 (2900 1000);
PAINT GREEN (2900 1000);
DISPLAY INVISIBLE (2900 1000);
FORCEADD OFFPAGE..2
(3700 1950);
FORCEPROP 2 LAST $XR0 108 
J 0
(3889 1950);
DISPLAY 0.638298 (3889 1950);
PAINT MONO (3889 1950);
FORCEPROP 1 LAST COMMENT_BODY TRUE
J 0
(3655 1855);
DISPLAY 0.872340 (3655 1855);
PAINT GREEN (3655 1855);
DISPLAY INVISIBLE (3655 1855);
FORCEPROP 2 LAST CDS_LIB mstr_standard
J 0
(3700 1950);
PAINT ORANGE (3700 1950);
DISPLAY INVISIBLE (3700 1950);
FORCEPROP 1 LAST OFFPAGE TRUE
J 0
(4025 1825);
DISPLAY 0.872340 (4025 1825);
PAINT GREEN (4025 1825);
DISPLAY INVISIBLE (4025 1825);
FORCEPROP 2 LAST PATH I128
J 0
(3875 2025);
DISPLAY 1.021277 (3875 2025);
PAINT ORANGE (3875 2025);
DISPLAY INVISIBLE (3875 2025);
FORCEADD OFFPAGE..2
(3700 1900);
FORCEPROP 2 LAST $XR0 108 
J 0
(3889 1900);
DISPLAY 0.638298 (3889 1900);
PAINT MONO (3889 1900);
FORCEPROP 1 LAST COMMENT_BODY TRUE
J 0
(3655 1805);
DISPLAY 0.872340 (3655 1805);
PAINT GREEN (3655 1805);
DISPLAY INVISIBLE (3655 1805);
FORCEPROP 2 LAST CDS_LIB mstr_standard
J 0
(3700 1900);
PAINT ORANGE (3700 1900);
DISPLAY INVISIBLE (3700 1900);
FORCEPROP 1 LAST OFFPAGE TRUE
J 0
(4025 1775);
DISPLAY 0.872340 (4025 1775);
PAINT GREEN (4025 1775);
DISPLAY INVISIBLE (4025 1775);
FORCEPROP 2 LAST PATH I129
J 0
(3875 1975);
DISPLAY 1.021277 (3875 1975);
PAINT ORANGE (3875 1975);
DISPLAY INVISIBLE (3875 1975);
FORCEADD OFFPAGE..1
(-2350 2300);
FORCEPROP 2 LAST $XR0 114 
J 0
(-2602 2300);
DISPLAY 0.638298 (-2602 2300);
PAINT MONO (-2602 2300);
FORCEPROP 2 LAST PATH I130
J 0
(-2625 2350);
DISPLAY 1.021277 (-2625 2350);
PAINT ORANGE (-2625 2350);
DISPLAY INVISIBLE (-2625 2350);
FORCEPROP 2 LAST CDS_LIB mstr_standard
J 0
(-2350 2300);
PAINT ORANGE (-2350 2300);
DISPLAY INVISIBLE (-2350 2300);
FORCEPROP 1 LAST COMMENT_BODY TRUE
J 0
(-2225 2200);
DISPLAY 0.872340 (-2225 2200);
PAINT PEACH (-2225 2200);
DISPLAY INVISIBLE (-2225 2200);
FORCEPROP 1 LAST OFFPAGE TRUE
J 0
(-2025 2175);
DISPLAY 0.872340 (-2025 2175);
PAINT GREEN (-2025 2175);
DISPLAY INVISIBLE (-2025 2175);
FORCEADD OFFPAGE..2
R 2
(-2350 2450);
FORCEPROP 2 LAST $XR0 111 
J 0
(-2605 2450);
DISPLAY 0.638298 (-2605 2450);
PAINT MONO (-2605 2450);
FORCEPROP 1 LAST OFFPAGE TRUE
J 2
(-2675 2325);
DISPLAY 0.872340 (-2675 2325);
PAINT GREEN (-2675 2325);
DISPLAY INVISIBLE (-2675 2325);
FORCEPROP 2 LAST PATH I133
J 0
(-2600 2500);
DISPLAY 1.021277 (-2600 2500);
PAINT ORANGE (-2600 2500);
DISPLAY INVISIBLE (-2600 2500);
FORCEPROP 1 LAST COMMENT_BODY TRUE
J 2
(-2305 2355);
DISPLAY 0.872340 (-2305 2355);
PAINT PEACH (-2305 2355);
DISPLAY INVISIBLE (-2305 2355);
FORCEPROP 2 LAST CDS_LIB mstr_standard
J 0
(-2350 2450);
PAINT ORANGE (-2350 2450);
DISPLAY INVISIBLE (-2350 2450);
FORCEADD OFFPAGE..2
R 2
(-2350 2400);
FORCEPROP 2 LAST $XR0 111 
J 0
(-2605 2400);
DISPLAY 0.638298 (-2605 2400);
PAINT MONO (-2605 2400);
FORCEPROP 1 LAST OFFPAGE TRUE
J 2
(-2675 2275);
DISPLAY 0.872340 (-2675 2275);
PAINT GREEN (-2675 2275);
DISPLAY INVISIBLE (-2675 2275);
FORCEPROP 2 LAST PATH I138
J 0
(-2600 2450);
DISPLAY 1.021277 (-2600 2450);
PAINT ORANGE (-2600 2450);
DISPLAY INVISIBLE (-2600 2450);
FORCEPROP 1 LAST COMMENT_BODY TRUE
J 2
(-2305 2305);
DISPLAY 0.872340 (-2305 2305);
PAINT PEACH (-2305 2305);
DISPLAY INVISIBLE (-2305 2305);
FORCEPROP 2 LAST CDS_LIB mstr_standard
J 0
(-2350 2400);
PAINT ORANGE (-2350 2400);
DISPLAY INVISIBLE (-2350 2400);
FORCEADD RES..1
(-1175 2800);
FORCEPROP 1 LAST WATTAGE 1/16W
J 2
(-1250 2750);
DISPLAY 0.617021 (-1250 2750);
PAINT SKYBLUE (-1250 2750);
FORCEPROP 1 LAST VALUE 0.0
J 2
(-1175 2750);
DISPLAY 0.617021 (-1175 2750);
PAINT SKYBLUE (-1175 2750);
FORCEPROP 1 LAST TOLERANCE 5%
J 0
(-1125 2750);
DISPLAY 0.617021 (-1125 2750);
PAINT SKYBLUE (-1125 2750);
FORCEPROP 1 LASTPIN (-1275 2800) $PN 1
J 0
(-1263 2812);
DISPLAY 0.617021 (-1263 2812);
PAINT ORANGE (-1263 2812);
FORCEPROP 1 LASTPIN (-1075 2800) $PN 2
J 0
(-1113 2812);
DISPLAY 0.617021 (-1113 2812);
PAINT ORANGE (-1113 2812);
FORCEPROP 1 LAST LOCATION R7C2
J 0
(-1200 2825);
DISPLAY 0.617021 (-1200 2825);
PAINT AQUA (-1200 2825);
FORCEPROP 1 LAST PART_NUMBER G21497-005
J 0
(-1225 2900);
DISPLAY 0.617021 (-1225 2900);
PAINT BLUE (-1225 2900);
FORCEPROP 1 LAST MATERIAL EMPTY
J 0
(-1050 2750);
DISPLAY 0.617021 (-1050 2750);
PAINT RED (-1050 2750);
FORCEPROP 1 LAST PACK_TYPE 0402
J 0
(-925 2750);
DISPLAY 0.617021 (-925 2750);
PAINT SKYBLUE (-925 2750);
FORCEPROP 2 LAST CDS_LIB mstr_discrete
J 0
(-1175 2800);
PAINT MONO (-1175 2800);
DISPLAY INVISIBLE (-1175 2800);
FORCEPROP 2 LAST CDS_LOCATION R7C2
J 0
(-1200 2825);
DISPLAY 0.617021 (-1200 2825);
PAINT AQUA (-1200 2825);
DISPLAY INVISIBLE (-1200 2825);
FORCEPROP 0 LAST ROOM SB
J 0
(-1200 2925);
DISPLAY 1.021277 (-1200 2925);
PAINT ORANGE (-1200 2925);
DISPLAY INVISIBLE (-1200 2925);
FORCEPROP 2 LAST SEC_TYPE 0402
J 0
(-1225 3000);
DISPLAY 1.021277 (-1225 3000);
PAINT ORANGE (-1225 3000);
DISPLAY INVISIBLE (-1225 3000);
FORCEPROP 2 LAST SEC 1
J 0
(-1225 3000);
DISPLAY 0.680851 (-1225 3000);
PAINT MONO (-1225 3000);
DISPLAY INVISIBLE (-1225 3000);
FORCEPROP 0 LAST BOM_COST SB
J 0
(-1200 3025);
DISPLAY 1.021277 (-1200 3025);
PAINT ORANGE (-1200 3025);
DISPLAY INVISIBLE (-1200 3025);
FORCEPROP 1 LAST PATH I141
J 0
(-1225 2950);
DISPLAY 0.978723 (-1225 2950);
PAINT WHITE (-1225 2950);
DISPLAY INVISIBLE (-1225 2950);
FORCEADD RES..1
(-1625 2850);
FORCEPROP 1 LAST WATTAGE 1/16W
J 2
(-1725 2800);
DISPLAY 0.617021 (-1725 2800);
PAINT SKYBLUE (-1725 2800);
FORCEPROP 1 LAST VALUE 0.0
J 2
(-1650 2800);
DISPLAY 0.617021 (-1650 2800);
PAINT SKYBLUE (-1650 2800);
FORCEPROP 1 LASTPIN (-1725 2850) $PN 1
J 0
(-1713 2862);
DISPLAY 0.617021 (-1713 2862);
PAINT ORANGE (-1713 2862);
FORCEPROP 1 LASTPIN (-1525 2850) $PN 2
J 0
(-1563 2862);
DISPLAY 0.617021 (-1563 2862);
PAINT ORANGE (-1563 2862);
FORCEPROP 1 LAST TOLERANCE 5%
J 0
(-1575 2800);
DISPLAY 0.617021 (-1575 2800);
PAINT SKYBLUE (-1575 2800);
FORCEPROP 1 LAST PART_NUMBER G21497-005
J 0
(-1675 2950);
DISPLAY 0.617021 (-1675 2950);
PAINT BLUE (-1675 2950);
FORCEPROP 1 LAST LOCATION R7C4
J 0
(-1650 2875);
DISPLAY 0.617021 (-1650 2875);
PAINT AQUA (-1650 2875);
FORCEPROP 1 LAST MATERIAL EMPTY
J 0
(-1500 2800);
DISPLAY 0.617021 (-1500 2800);
PAINT RED (-1500 2800);
FORCEPROP 1 LAST PACK_TYPE 0402
J 0
(-1375 2800);
DISPLAY 0.617021 (-1375 2800);
PAINT SKYBLUE (-1375 2800);
FORCEPROP 1 LAST PATH I142
J 0
(-1675 3000);
DISPLAY 0.978723 (-1675 3000);
PAINT WHITE (-1675 3000);
DISPLAY INVISIBLE (-1675 3000);
FORCEPROP 2 LAST CDS_LOCATION R7C4
J 0
(-1650 2875);
DISPLAY 0.617021 (-1650 2875);
PAINT AQUA (-1650 2875);
DISPLAY INVISIBLE (-1650 2875);
FORCEPROP 2 LAST CDS_LIB mstr_discrete
J 0
(-1625 2850);
PAINT MONO (-1625 2850);
DISPLAY INVISIBLE (-1625 2850);
FORCEPROP 0 LAST ROOM SB
J 0
(-1650 2975);
DISPLAY 1.021277 (-1650 2975);
PAINT ORANGE (-1650 2975);
DISPLAY INVISIBLE (-1650 2975);
FORCEPROP 2 LAST SEC 1
J 0
(-1675 3050);
DISPLAY 0.680851 (-1675 3050);
PAINT MONO (-1675 3050);
DISPLAY INVISIBLE (-1675 3050);
FORCEPROP 2 LAST SEC_TYPE 0402
J 0
(-1675 3050);
DISPLAY 1.021277 (-1675 3050);
PAINT ORANGE (-1675 3050);
DISPLAY INVISIBLE (-1675 3050);
FORCEPROP 0 LAST BOM_COST SB
J 0
(-1650 3075);
DISPLAY 1.021277 (-1650 3075);
PAINT ORANGE (-1650 3075);
DISPLAY INVISIBLE (-1650 3075);
FORCEADD OFFPAGE..5
(-2350 2850);
FORCEPROP 2 LAST $XR0 145 
J 0
(-2605 2850);
DISPLAY 0.638298 (-2605 2850);
PAINT MONO (-2605 2850);
FORCEPROP 2 LAST CDS_LIB mstr_standard
J 0
(-2350 2850);
PAINT ORANGE (-2350 2850);
DISPLAY INVISIBLE (-2350 2850);
FORCEPROP 2 LAST PATH I143
J 0
(-2300 2925);
DISPLAY 1.021277 (-2300 2925);
PAINT ORANGE (-2300 2925);
DISPLAY INVISIBLE (-2300 2925);
FORCEPROP 1 LAST COMMENT_BODY TRUE
J 0
(-2250 2775);
DISPLAY 0.872340 (-2250 2775);
PAINT GREEN (-2250 2775);
DISPLAY INVISIBLE (-2250 2775);
FORCEPROP 1 LAST OFFPAGE TRUE
J 0
(-2025 2725);
DISPLAY 0.872340 (-2025 2725);
PAINT GREEN (-2025 2725);
DISPLAY INVISIBLE (-2025 2725);
FORCEADD RES..2
(-2950 2750);
FORCEPROP 1 LAST VALUE 169
J 0
(-2905 2825);
DISPLAY 0.617021 (-2905 2825);
PAINT SKYBLUE (-2905 2825);
FORCEPROP 1 LAST WATTAGE 1/16W
J 0
(-2910 2725);
DISPLAY 0.617021 (-2910 2725);
PAINT SKYBLUE (-2910 2725);
FORCEPROP 1 LAST MATERIAL CHIP
J 0
(-2910 2675);
DISPLAY 0.617021 (-2910 2675);
PAINT SKYBLUE (-2910 2675);
FORCEPROP 1 LAST PACK_TYPE 0402
J 0
(-2910 2575);
DISPLAY 0.617021 (-2910 2575);
PAINT SKYBLUE (-2910 2575);
FORCEPROP 1 LAST TOLERANCE 1.0%
J 0
(-2905 2775);
DISPLAY 0.617021 (-2905 2775);
PAINT SKYBLUE (-2905 2775);
FORCEPROP 1 LAST PART_NUMBER G21796-276
J 0
(-2910 2625);
DISPLAY 0.617021 (-2910 2625);
PAINT BLUE (-2910 2625);
FORCEPROP 1 LAST LOCATION R3N1
J 0
(-2905 2875);
DISPLAY 0.617021 (-2905 2875);
PAINT AQUA (-2905 2875);
FORCEPROP 1 LASTPIN (-2950 2650) $PN 2
J 0
(-2945 2660);
DISPLAY 0.787234 (-2945 2660);
PAINT ORANGE (-2945 2660);
DISPLAY INVISIBLE (-2945 2660);
FORCEPROP 2 LAST CDS_LIB mstr_discrete
J 0
(-2950 2750);
PAINT ORANGE (-2950 2750);
DISPLAY INVISIBLE (-2950 2750);
FORCEPROP 1 LASTPIN (-2950 2850) $PN 1
J 0
(-2945 2812);
DISPLAY 0.787234 (-2945 2812);
PAINT ORANGE (-2945 2812);
DISPLAY INVISIBLE (-2945 2812);
FORCEPROP 0 LAST ROOM SB
J 0
(-2900 2975);
DISPLAY 1.021277 (-2900 2975);
PAINT ORANGE (-2900 2975);
DISPLAY INVISIBLE (-2900 2975);
FORCEPROP 1 LAST PATH I149
J 0
(-2900 2925);
DISPLAY 0.978723 (-2900 2925);
PAINT WHITE (-2900 2925);
DISPLAY INVISIBLE (-2900 2925);
FORCEPROP 2 LAST CDS_LOCATION R3N1
J 0
(-2905 2875);
DISPLAY 0.617021 (-2905 2875);
PAINT AQUA (-2905 2875);
DISPLAY INVISIBLE (-2905 2875);
FORCEPROP 2 LAST CDS_SEC 1
J 0
(-2900 2975);
DISPLAY 1.021277 (-2900 2975);
PAINT ORANGE (-2900 2975);
DISPLAY INVISIBLE (-2900 2975);
FORCEPROP 2 LAST $SEC 1
J 0
(-2900 2975);
DISPLAY 0.680851 (-2900 2975);
PAINT MONO (-2900 2975);
DISPLAY INVISIBLE (-2900 2975);
FORCEADD GND..1
(-2950 2500);
FORCEPROP 3 LASTPIN (-2950 2550) SIG_NAME GND\g
J 0
(-2940 2560);
DISPLAY 0.659574 (-2940 2560);
PAINT MONO (-2940 2560);
DISPLAY INVISIBLE (-2940 2560);
FORCEPROP 1 LAST VOLTAGE 0.0V
J 0
(-2995 2457);
DISPLAY 0.340426 (-2995 2457);
PAINT SKYBLUE (-2995 2457);
DISPLAY INVISIBLE (-2995 2457);
FORCEPROP 2 LAST CDS_LIB mstr_symbols
J 0
(-2950 2500);
PAINT ORANGE (-2950 2500);
DISPLAY INVISIBLE (-2950 2500);
FORCEPROP 1 LAST SIZE 1B
J 0
(-2875 2450);
DISPLAY 0.872340 (-2875 2450);
PAINT AQUA (-2875 2450);
DISPLAY INVISIBLE (-2875 2450);
FORCEPROP 1 LAST BODY_TYPE PLUMBING
J 0
(-2995 2457);
DISPLAY 0.340426 (-2995 2457);
PAINT GREEN (-2995 2457);
DISPLAY INVISIBLE (-2995 2457);
FORCEPROP 1 LAST PATH I150
J 0
(-2875 2500);
DISPLAY 0.872340 (-2875 2500);
PAINT AQUA (-2875 2500);
DISPLAY INVISIBLE (-2875 2500);
FORCEPROP 1 LAST HDL_POWER GND
J 0
(-2950 2650);
DISPLAY 0.872340 (-2950 2650);
PAINT GREEN (-2950 2650);
DISPLAY INVISIBLE (-2950 2650);
FORCEADD OFFPAGE..2
(3700 2650);
FORCEPROP 2 LAST $XR0 187 
J 0
(3889 2650);
DISPLAY 0.638298 (3889 2650);
PAINT MONO (3889 2650);
FORCEPROP 1 LAST COMMENT_BODY TRUE
J 0
(3655 2555);
DISPLAY 0.872340 (3655 2555);
PAINT PEACH (3655 2555);
DISPLAY INVISIBLE (3655 2555);
FORCEPROP 1 LAST OFFPAGE TRUE
J 0
(4025 2525);
DISPLAY 0.872340 (4025 2525);
PAINT GREEN (4025 2525);
DISPLAY INVISIBLE (4025 2525);
FORCEPROP 2 LAST CDS_LIB mstr_standard
J 0
(3700 2650);
PAINT ORANGE (3700 2650);
DISPLAY INVISIBLE (3700 2650);
FORCEPROP 2 LAST PATH I166
J 0
(3900 2700);
DISPLAY 1.021277 (3900 2700);
PAINT ORANGE (3900 2700);
DISPLAY INVISIBLE (3900 2700);
FORCEADD OFFPAGE..2
(3700 2600);
FORCEPROP 2 LAST $XR0 187 
J 0
(3889 2600);
DISPLAY 0.638298 (3889 2600);
PAINT MONO (3889 2600);
FORCEPROP 1 LAST COMMENT_BODY TRUE
J 0
(3655 2505);
DISPLAY 0.872340 (3655 2505);
PAINT PEACH (3655 2505);
DISPLAY INVISIBLE (3655 2505);
FORCEPROP 1 LAST OFFPAGE TRUE
J 0
(4025 2475);
DISPLAY 0.872340 (4025 2475);
PAINT GREEN (4025 2475);
DISPLAY INVISIBLE (4025 2475);
FORCEPROP 2 LAST CDS_LIB mstr_standard
J 0
(3700 2600);
PAINT ORANGE (3700 2600);
DISPLAY INVISIBLE (3700 2600);
FORCEPROP 2 LAST PATH I167
J 0
(3900 2650);
DISPLAY 1.021277 (3900 2650);
PAINT ORANGE (3900 2650);
DISPLAY INVISIBLE (3900 2650);
FORCEADD OFFPAGE..2
(3700 2500);
FORCEPROP 2 LAST $XR0 187 
J 0
(3889 2500);
DISPLAY 0.638298 (3889 2500);
PAINT MONO (3889 2500);
FORCEPROP 1 LAST COMMENT_BODY TRUE
J 0
(3655 2405);
DISPLAY 0.872340 (3655 2405);
PAINT PEACH (3655 2405);
DISPLAY INVISIBLE (3655 2405);
FORCEPROP 2 LAST CDS_LIB mstr_standard
J 0
(3700 2500);
PAINT ORANGE (3700 2500);
DISPLAY INVISIBLE (3700 2500);
FORCEPROP 1 LAST OFFPAGE TRUE
J 0
(4025 2375);
DISPLAY 0.872340 (4025 2375);
PAINT GREEN (4025 2375);
DISPLAY INVISIBLE (4025 2375);
FORCEPROP 2 LAST PATH I168
J 0
(3900 2550);
DISPLAY 1.021277 (3900 2550);
PAINT ORANGE (3900 2550);
DISPLAY INVISIBLE (3900 2550);
FORCEADD OFFPAGE..2
(3700 2550);
FORCEPROP 2 LAST $XR0 187 
J 0
(3889 2550);
DISPLAY 0.638298 (3889 2550);
PAINT MONO (3889 2550);
FORCEPROP 1 LAST COMMENT_BODY TRUE
J 0
(3655 2455);
DISPLAY 0.872340 (3655 2455);
PAINT PEACH (3655 2455);
DISPLAY INVISIBLE (3655 2455);
FORCEPROP 1 LAST OFFPAGE TRUE
J 0
(4025 2425);
DISPLAY 0.872340 (4025 2425);
PAINT GREEN (4025 2425);
DISPLAY INVISIBLE (4025 2425);
FORCEPROP 2 LAST CDS_LIB mstr_standard
J 0
(3700 2550);
PAINT ORANGE (3700 2550);
DISPLAY INVISIBLE (3700 2550);
FORCEPROP 2 LAST PATH I169
J 0
(3900 2600);
DISPLAY 1.021277 (3900 2600);
PAINT ORANGE (3900 2600);
DISPLAY INVISIBLE (3900 2600);
FORCEADD OFFPAGE..2
(3700 2400);
FORCEPROP 2 LAST $XR0 186 
J 0
(3889 2400);
DISPLAY 0.638298 (3889 2400);
PAINT MONO (3889 2400);
FORCEPROP 1 LAST COMMENT_BODY TRUE
J 0
(3655 2305);
DISPLAY 0.872340 (3655 2305);
PAINT PEACH (3655 2305);
DISPLAY INVISIBLE (3655 2305);
FORCEPROP 2 LAST CDS_LIB mstr_standard
J 0
(3700 2400);
PAINT ORANGE (3700 2400);
DISPLAY INVISIBLE (3700 2400);
FORCEPROP 1 LAST OFFPAGE TRUE
J 0
(4025 2275);
DISPLAY 0.872340 (4025 2275);
PAINT GREEN (4025 2275);
DISPLAY INVISIBLE (4025 2275);
FORCEPROP 2 LAST PATH I170
J 0
(3900 2450);
DISPLAY 1.021277 (3900 2450);
PAINT ORANGE (3900 2450);
DISPLAY INVISIBLE (3900 2450);
FORCEADD OFFPAGE..2
(3700 2450);
FORCEPROP 2 LAST $XR0 186 
J 0
(3889 2450);
DISPLAY 0.638298 (3889 2450);
PAINT MONO (3889 2450);
FORCEPROP 1 LAST COMMENT_BODY TRUE
J 0
(3655 2355);
DISPLAY 0.872340 (3655 2355);
PAINT PEACH (3655 2355);
DISPLAY INVISIBLE (3655 2355);
FORCEPROP 2 LAST CDS_LIB mstr_standard
J 0
(3700 2450);
PAINT ORANGE (3700 2450);
DISPLAY INVISIBLE (3700 2450);
FORCEPROP 1 LAST OFFPAGE TRUE
J 0
(4025 2325);
DISPLAY 0.872340 (4025 2325);
PAINT GREEN (4025 2325);
DISPLAY INVISIBLE (4025 2325);
FORCEPROP 2 LAST PATH I171
J 0
(3900 2500);
DISPLAY 1.021277 (3900 2500);
PAINT ORANGE (3900 2500);
DISPLAY INVISIBLE (3900 2500);
FORCEADD OFFPAGE..2
(3700 2350);
FORCEPROP 2 LAST $XR0 186 
J 0
(3889 2350);
DISPLAY 0.638298 (3889 2350);
PAINT MONO (3889 2350);
FORCEPROP 1 LAST COMMENT_BODY TRUE
J 0
(3655 2255);
DISPLAY 0.872340 (3655 2255);
PAINT PEACH (3655 2255);
DISPLAY INVISIBLE (3655 2255);
FORCEPROP 2 LAST CDS_LIB mstr_standard
J 0
(3700 2350);
PAINT ORANGE (3700 2350);
DISPLAY INVISIBLE (3700 2350);
FORCEPROP 1 LAST OFFPAGE TRUE
J 0
(4025 2225);
DISPLAY 0.872340 (4025 2225);
PAINT GREEN (4025 2225);
DISPLAY INVISIBLE (4025 2225);
FORCEPROP 2 LAST PATH I172
J 0
(3900 2400);
DISPLAY 1.021277 (3900 2400);
PAINT ORANGE (3900 2400);
DISPLAY INVISIBLE (3900 2400);
FORCEADD OFFPAGE..2
(3700 2300);
FORCEPROP 2 LAST $XR0 186 
J 0
(3889 2300);
DISPLAY 0.638298 (3889 2300);
PAINT MONO (3889 2300);
FORCEPROP 1 LAST COMMENT_BODY TRUE
J 0
(3655 2205);
DISPLAY 0.872340 (3655 2205);
PAINT PEACH (3655 2205);
DISPLAY INVISIBLE (3655 2205);
FORCEPROP 2 LAST CDS_LIB mstr_standard
J 0
(3700 2300);
PAINT ORANGE (3700 2300);
DISPLAY INVISIBLE (3700 2300);
FORCEPROP 1 LAST OFFPAGE TRUE
J 0
(4025 2175);
DISPLAY 0.872340 (4025 2175);
PAINT GREEN (4025 2175);
DISPLAY INVISIBLE (4025 2175);
FORCEPROP 2 LAST PATH I173
J 0
(3900 2350);
DISPLAY 1.021277 (3900 2350);
PAINT ORANGE (3900 2350);
DISPLAY INVISIBLE (3900 2350);
FORCEADD OFFPAGE..5
R 2
(3700 3050);
FORCEPROP 2 LAST $XR0 185 
J 0
(3889 3050);
DISPLAY 0.638298 (3889 3050);
PAINT MONO (3889 3050);
FORCEPROP 1 LAST OFFPAGE TRUE
J 2
(3375 2925);
DISPLAY 0.872340 (3375 2925);
PAINT GREEN (3375 2925);
DISPLAY INVISIBLE (3375 2925);
FORCEPROP 1 LAST COMMENT_BODY TRUE
J 2
(3600 2975);
DISPLAY 0.872340 (3600 2975);
PAINT GREEN (3600 2975);
DISPLAY INVISIBLE (3600 2975);
FORCEPROP 2 LAST CDS_LIB mstr_standard
J 0
(3700 3050);
PAINT ORANGE (3700 3050);
DISPLAY INVISIBLE (3700 3050);
FORCEPROP 2 LAST PATH I174
J 0
(3450 3100);
DISPLAY 1.021277 (3450 3100);
PAINT ORANGE (3450 3100);
DISPLAY INVISIBLE (3450 3100);
FORCEADD OFFPAGE..5
R 2
(3700 3000);
FORCEPROP 2 LAST $XR0 185 
J 0
(3889 3000);
DISPLAY 0.638298 (3889 3000);
PAINT MONO (3889 3000);
FORCEPROP 1 LAST OFFPAGE TRUE
J 2
(3375 2875);
DISPLAY 0.872340 (3375 2875);
PAINT GREEN (3375 2875);
DISPLAY INVISIBLE (3375 2875);
FORCEPROP 1 LAST COMMENT_BODY TRUE
J 2
(3600 2925);
DISPLAY 0.872340 (3600 2925);
PAINT GREEN (3600 2925);
DISPLAY INVISIBLE (3600 2925);
FORCEPROP 2 LAST CDS_LIB mstr_standard
J 0
(3700 3000);
PAINT ORANGE (3700 3000);
DISPLAY INVISIBLE (3700 3000);
FORCEPROP 2 LAST PATH I175
J 0
(3450 3050);
DISPLAY 1.021277 (3450 3050);
PAINT ORANGE (3450 3050);
DISPLAY INVISIBLE (3450 3050);
FORCEADD OFFPAGE..5
(-2350 2800);
FORCEPROP 2 LAST $XR0 145 
J 0
(-2605 2800);
DISPLAY 0.638298 (-2605 2800);
PAINT MONO (-2605 2800);
FORCEPROP 2 LAST PATH I180
J 0
(-2600 2850);
DISPLAY 1.021277 (-2600 2850);
PAINT ORANGE (-2600 2850);
DISPLAY INVISIBLE (-2600 2850);
FORCEPROP 2 LAST CDS_LIB mstr_standard
J 0
(-2350 2800);
PAINT ORANGE (-2350 2800);
DISPLAY INVISIBLE (-2350 2800);
FORCEPROP 1 LAST COMMENT_BODY TRUE
J 0
(-2250 2725);
DISPLAY 0.872340 (-2250 2725);
PAINT GREEN (-2250 2725);
DISPLAY INVISIBLE (-2250 2725);
FORCEPROP 1 LAST OFFPAGE TRUE
J 0
(-2025 2675);
DISPLAY 0.872340 (-2025 2675);
PAINT GREEN (-2025 2675);
DISPLAY INVISIBLE (-2025 2675);
FORCEADD OFFPAGE..2
(3700 2900);
FORCEPROP 2 LAST $XR0 139 
J 0
(3889 2900);
DISPLAY 0.638298 (3889 2900);
PAINT MONO (3889 2900);
FORCEPROP 2 LAST PATH I181
J 0
(3450 2950);
DISPLAY 1.021277 (3450 2950);
PAINT ORANGE (3450 2950);
DISPLAY INVISIBLE (3450 2950);
FORCEPROP 1 LAST COMMENT_BODY TRUE
J 0
(3655 2805);
DISPLAY 0.872340 (3655 2805);
PAINT GREEN (3655 2805);
DISPLAY INVISIBLE (3655 2805);
FORCEPROP 2 LAST CDS_LIB mstr_standard
J 0
(3700 2900);
PAINT ORANGE (3700 2900);
DISPLAY INVISIBLE (3700 2900);
FORCEPROP 1 LAST OFFPAGE TRUE
J 0
(4025 2775);
DISPLAY 0.872340 (4025 2775);
PAINT GREEN (4025 2775);
DISPLAY INVISIBLE (4025 2775);
FORCEADD OFFPAGE..2
(3700 2950);
FORCEPROP 2 LAST $XR0 139 
J 0
(3889 2950);
DISPLAY 0.638298 (3889 2950);
PAINT MONO (3889 2950);
FORCEPROP 2 LAST PATH I182
J 0
(3450 3000);
DISPLAY 1.021277 (3450 3000);
PAINT ORANGE (3450 3000);
DISPLAY INVISIBLE (3450 3000);
FORCEPROP 1 LAST COMMENT_BODY TRUE
J 0
(3655 2855);
DISPLAY 0.872340 (3655 2855);
PAINT GREEN (3655 2855);
DISPLAY INVISIBLE (3655 2855);
FORCEPROP 2 LAST CDS_LIB mstr_standard
J 0
(3700 2950);
PAINT ORANGE (3700 2950);
DISPLAY INVISIBLE (3700 2950);
FORCEPROP 1 LAST OFFPAGE TRUE
J 0
(4025 2825);
DISPLAY 0.872340 (4025 2825);
PAINT GREEN (4025 2825);
DISPLAY INVISIBLE (4025 2825);
FORCEADD OFFPAGE..2
(3700 1550);
FORCEPROP 2 LAST $XR0 181 
J 0
(3889 1550);
DISPLAY 0.638298 (3889 1550);
PAINT MONO (3889 1550);
FORCEPROP 1 LAST COMMENT_BODY TRUE
J 0
(3655 1455);
DISPLAY 0.872340 (3655 1455);
PAINT PEACH (3655 1455);
DISPLAY INVISIBLE (3655 1455);
FORCEPROP 1 LAST OFFPAGE TRUE
J 0
(4025 1425);
DISPLAY 0.872340 (4025 1425);
PAINT GREEN (4025 1425);
DISPLAY INVISIBLE (4025 1425);
FORCEPROP 2 LAST CDS_LIB mstr_standard
J 0
(3700 1550);
PAINT ORANGE (3700 1550);
DISPLAY INVISIBLE (3700 1550);
FORCEPROP 2 LAST PATH I183
J 0
(3900 1600);
DISPLAY 1.021277 (3900 1600);
PAINT ORANGE (3900 1600);
DISPLAY INVISIBLE (3900 1600);
FORCEADD OFFPAGE..2
(3700 1500);
FORCEPROP 2 LAST $XR0 181 
J 0
(3889 1500);
DISPLAY 0.638298 (3889 1500);
PAINT MONO (3889 1500);
FORCEPROP 1 LAST COMMENT_BODY TRUE
J 0
(3655 1405);
DISPLAY 0.872340 (3655 1405);
PAINT PEACH (3655 1405);
DISPLAY INVISIBLE (3655 1405);
FORCEPROP 1 LAST OFFPAGE TRUE
J 0
(4025 1375);
DISPLAY 0.872340 (4025 1375);
PAINT GREEN (4025 1375);
DISPLAY INVISIBLE (4025 1375);
FORCEPROP 2 LAST CDS_LIB mstr_standard
J 0
(3700 1500);
PAINT ORANGE (3700 1500);
DISPLAY INVISIBLE (3700 1500);
FORCEPROP 2 LAST PATH I184
J 0
(3900 1550);
DISPLAY 1.021277 (3900 1550);
PAINT ORANGE (3900 1550);
DISPLAY INVISIBLE (3900 1550);
FORCEADD OFFPAGE..2
(3700 1650);
FORCEPROP 2 LAST $XR0 102 
J 0
(3889 1650);
DISPLAY 0.638298 (3889 1650);
PAINT MONO (3889 1650);
FORCEPROP 1 LAST OFFPAGE TRUE
J 0
(4025 1525);
DISPLAY 0.872340 (4025 1525);
PAINT GREEN (4025 1525);
DISPLAY INVISIBLE (4025 1525);
FORCEPROP 1 LAST COMMENT_BODY TRUE
J 0
(3655 1555);
DISPLAY 0.872340 (3655 1555);
PAINT PEACH (3655 1555);
DISPLAY INVISIBLE (3655 1555);
FORCEPROP 2 LAST CDS_LIB mstr_standard
J 0
(3700 1650);
PAINT ORANGE (3700 1650);
DISPLAY INVISIBLE (3700 1650);
FORCEPROP 2 LAST PATH I185
J 0
(3900 1700);
DISPLAY 1.021277 (3900 1700);
PAINT ORANGE (3900 1700);
DISPLAY INVISIBLE (3900 1700);
FORCEADD OFFPAGE..2
(3700 1600);
FORCEPROP 2 LAST $XR0 102 
J 0
(3889 1600);
DISPLAY 0.638298 (3889 1600);
PAINT MONO (3889 1600);
FORCEPROP 1 LAST OFFPAGE TRUE
J 0
(4025 1475);
DISPLAY 0.872340 (4025 1475);
PAINT GREEN (4025 1475);
DISPLAY INVISIBLE (4025 1475);
FORCEPROP 1 LAST COMMENT_BODY TRUE
J 0
(3655 1505);
DISPLAY 0.872340 (3655 1505);
PAINT PEACH (3655 1505);
DISPLAY INVISIBLE (3655 1505);
FORCEPROP 2 LAST CDS_LIB mstr_standard
J 0
(3700 1600);
PAINT ORANGE (3700 1600);
DISPLAY INVISIBLE (3700 1600);
FORCEPROP 2 LAST PATH I186
J 0
(3900 1650);
DISPLAY 1.021277 (3900 1650);
PAINT ORANGE (3900 1650);
DISPLAY INVISIBLE (3900 1650);
FORCEADD OFFPAGE..5
R 2
(3700 2850);
FORCEPROP 2 LAST $XR0 245 
J 0
(3890 2850);
DISPLAY 0.638298 (3890 2850);
PAINT MONO (3890 2850);
FORCEPROP 2 LAST CDS_LIB mstr_standard
J 0
(3700 2850);
PAINT MONO (3700 2850);
DISPLAY INVISIBLE (3700 2850);
FORCEPROP 2 LAST PATH I187
J 0
(3875 2925);
DISPLAY 1.021277 (3875 2925);
PAINT ORANGE (3875 2925);
DISPLAY INVISIBLE (3875 2925);
FORCEPROP 1 LAST COMMENT_BODY TRUE
J 2
(3600 2775);
DISPLAY 0.872340 (3600 2775);
PAINT GREEN (3600 2775);
DISPLAY INVISIBLE (3600 2775);
FORCEPROP 1 LAST OFFPAGE TRUE
J 2
(3375 2725);
DISPLAY 0.872340 (3375 2725);
PAINT GREEN (3375 2725);
DISPLAY INVISIBLE (3375 2725);
FORCEADD OFFPAGE..5
R 2
(3700 2800);
FORCEPROP 2 LAST $XR0 245 
J 0
(3905 2800);
DISPLAY 0.638298 (3905 2800);
PAINT MONO (3905 2800);
FORCEPROP 2 LAST CDS_LIB mstr_standard
J 0
(3700 2800);
PAINT MONO (3700 2800);
DISPLAY INVISIBLE (3700 2800);
FORCEPROP 2 LAST PATH I188
J 0
(3875 2875);
DISPLAY 1.021277 (3875 2875);
PAINT ORANGE (3875 2875);
DISPLAY INVISIBLE (3875 2875);
FORCEPROP 1 LAST COMMENT_BODY TRUE
J 2
(3600 2725);
DISPLAY 0.872340 (3600 2725);
PAINT GREEN (3600 2725);
DISPLAY INVISIBLE (3600 2725);
FORCEPROP 1 LAST OFFPAGE TRUE
J 2
(3375 2675);
DISPLAY 0.872340 (3375 2675);
PAINT GREEN (3375 2675);
DISPLAY INVISIBLE (3375 2675);
FORCEADD OFFPAGE..2
(3700 2750);
FORCEPROP 2 LAST $XR0 245 
J 0
(3905 2750);
DISPLAY 0.638298 (3905 2750);
PAINT MONO (3905 2750);
FORCEPROP 2 LAST CDS_LIB mstr_standard
J 0
(3700 2750);
PAINT MONO (3700 2750);
DISPLAY INVISIBLE (3700 2750);
FORCEPROP 2 LAST PATH I189
J 0
(3875 2825);
DISPLAY 1.021277 (3875 2825);
PAINT ORANGE (3875 2825);
DISPLAY INVISIBLE (3875 2825);
FORCEPROP 1 LAST OFFPAGE TRUE
J 0
(4025 2625);
DISPLAY 0.872340 (4025 2625);
PAINT GREEN (4025 2625);
DISPLAY INVISIBLE (4025 2625);
FORCEPROP 1 LAST COMMENT_BODY TRUE
J 0
(3655 2655);
DISPLAY 0.872340 (3655 2655);
PAINT GREEN (3655 2655);
DISPLAY INVISIBLE (3655 2655);
FORCEADD OFFPAGE..2
(3700 2700);
FORCEPROP 2 LAST $XR0 245 
J 0
(3905 2700);
DISPLAY 0.638298 (3905 2700);
PAINT MONO (3905 2700);
FORCEPROP 2 LAST CDS_LIB mstr_standard
J 0
(3700 2700);
PAINT MONO (3700 2700);
DISPLAY INVISIBLE (3700 2700);
FORCEPROP 2 LAST PATH I190
J 0
(3875 2775);
DISPLAY 1.021277 (3875 2775);
PAINT ORANGE (3875 2775);
DISPLAY INVISIBLE (3875 2775);
FORCEPROP 1 LAST OFFPAGE TRUE
J 0
(4025 2575);
DISPLAY 0.872340 (4025 2575);
PAINT GREEN (4025 2575);
DISPLAY INVISIBLE (4025 2575);
FORCEPROP 1 LAST COMMENT_BODY TRUE
J 0
(3655 2605);
DISPLAY 0.872340 (3655 2605);
PAINT GREEN (3655 2605);
DISPLAY INVISIBLE (3655 2605);
FORCEADD OFFPAGE..2
(3700 1700);
FORCEPROP 2 LAST $XR0 108 
J 0
(3889 1700);
DISPLAY 0.638298 (3889 1700);
PAINT MONO (3889 1700);
FORCEPROP 1 LAST COMMENT_BODY TRUE
J 0
(3655 1605);
DISPLAY 0.872340 (3655 1605);
PAINT PEACH (3655 1605);
DISPLAY INVISIBLE (3655 1605);
FORCEPROP 2 LAST CDS_LIB mstr_standard
J 0
(3700 1700);
PAINT ORANGE (3700 1700);
DISPLAY INVISIBLE (3700 1700);
FORCEPROP 1 LAST OFFPAGE TRUE
J 0
(4025 1575);
DISPLAY 0.872340 (4025 1575);
PAINT GREEN (4025 1575);
DISPLAY INVISIBLE (4025 1575);
FORCEPROP 2 LAST PATH I35
J 0
(3875 1775);
DISPLAY 1.021277 (3875 1775);
PAINT ORANGE (3875 1775);
DISPLAY INVISIBLE (3875 1775);
FORCEADD OFFPAGE..2
(3700 1750);
FORCEPROP 2 LAST $XR0 108 
J 0
(3889 1750);
DISPLAY 0.638298 (3889 1750);
PAINT MONO (3889 1750);
FORCEPROP 1 LAST COMMENT_BODY TRUE
J 0
(3655 1655);
DISPLAY 0.872340 (3655 1655);
PAINT PEACH (3655 1655);
DISPLAY INVISIBLE (3655 1655);
FORCEPROP 2 LAST CDS_LIB mstr_standard
J 0
(3700 1750);
PAINT ORANGE (3700 1750);
DISPLAY INVISIBLE (3700 1750);
FORCEPROP 1 LAST OFFPAGE TRUE
J 0
(4025 1625);
DISPLAY 0.872340 (4025 1625);
PAINT GREEN (4025 1625);
DISPLAY INVISIBLE (4025 1625);
FORCEPROP 2 LAST PATH I36
J 0
(3875 1825);
DISPLAY 1.021277 (3875 1825);
PAINT ORANGE (3875 1825);
DISPLAY INVISIBLE (3875 1825);
FORCEADD LBG_CORE_QAT_EXT_D..1
(525 2150);
FORCEPROP 2 LASTPIN (-475 1350) $PN D35
J 2
(-485 1360);
DISPLAY 0.617021 (-485 1360);
PAINT ORANGE (-485 1360);
FORCEPROP 2 LASTPIN (-475 1700) $PN B35
J 2
(-485 1710);
DISPLAY 0.617021 (-485 1710);
PAINT ORANGE (-485 1710);
FORCEPROP 2 LASTPIN (-475 1900) $PN H17
J 2
(-485 1910);
DISPLAY 0.617021 (-485 1910);
PAINT ORANGE (-485 1910);
FORCEPROP 1 LAST PART_NUMBER H91415-002
J 0
(-425 1100);
DISPLAY 0.617021 (-425 1100);
PAINT BLUE (-425 1100);
FORCEPROP 2 LASTPIN (-475 2950) $PN G44
J 2
(-485 2960);
DISPLAY 0.617021 (-485 2960);
PAINT ORANGE (-485 2960);
FORCEPROP 2 LASTPIN (-475 2300) $PN K17
J 2
(-485 2310);
DISPLAY 0.617021 (-485 2310);
PAINT ORANGE (-485 2310);
FORCEPROP 2 LASTPIN (-475 3000) $PN C26
J 2
(-485 3010);
DISPLAY 0.617021 (-485 3010);
PAINT ORANGE (-485 3010);
FORCEPROP 2 LASTPIN (-475 2650) $PN D40
J 2
(-485 2660);
DISPLAY 0.617021 (-485 2660);
PAINT ORANGE (-485 2660);
FORCEPROP 2 LASTPIN (-475 2600) $PN B40
J 2
(-485 2610);
DISPLAY 0.617021 (-485 2610);
PAINT ORANGE (-485 2610);
FORCEPROP 2 LASTPIN (-475 2850) $PN D29
J 2
(-485 2860);
DISPLAY 0.617021 (-485 2860);
PAINT ORANGE (-485 2860);
FORCEPROP 2 LASTPIN (-475 2800) $PN B29
J 2
(-485 2810);
DISPLAY 0.617021 (-485 2810);
PAINT ORANGE (-485 2810);
FORCEPROP 2 LASTPIN (-475 2550) $PN D38
J 2
(-485 2560);
DISPLAY 0.617021 (-485 2560);
PAINT ORANGE (-485 2560);
FORCEPROP 2 LASTPIN (-475 2500) $PN B38
J 2
(-485 2510);
DISPLAY 0.617021 (-485 2510);
PAINT ORANGE (-485 2510);
FORCEPROP 2 LASTPIN (-475 2750) $PN C32
J 2
(-485 2760);
DISPLAY 0.617021 (-485 2760);
PAINT ORANGE (-485 2760);
FORCEPROP 2 LASTPIN (-475 2700) $PN A32
J 2
(-485 2710);
DISPLAY 0.617021 (-485 2710);
PAINT ORANGE (-485 2710);
FORCEPROP 2 LASTPIN (-475 2450) $PN C39
J 2
(-485 2460);
DISPLAY 0.617021 (-485 2460);
PAINT ORANGE (-485 2460);
FORCEPROP 2 LASTPIN (-475 2400) $PN A39
J 2
(-485 2410);
DISPLAY 0.617021 (-485 2410);
PAINT ORANGE (-485 2410);
FORCEPROP 2 LASTPIN (-475 3050) $PN A26
J 2
(-485 3060);
DISPLAY 0.617021 (-485 3060);
PAINT ORANGE (-485 3060);
FORCEPROP 1 LAST MATERIAL IC
J 0
(-425 3250);
DISPLAY 0.617021 (-425 3250);
PAINT SKYBLUE (-425 3250);
FORCEPROP 1 LAST LOCATION U7C1
J 0
(-380 3332);
DISPLAY 0.617021 (-380 3332);
PAINT AQUA (-380 3332);
FORCEPROP 2 LASTPIN (1525 1400) $PN BV51
J 0
(1535 1410);
DISPLAY 0.617021 (1535 1410);
PAINT ORANGE (1535 1410);
FORCEPROP 2 LASTPIN (1525 1350) $PN BY51
J 0
(1535 1360);
DISPLAY 0.617021 (1535 1360);
PAINT ORANGE (1535 1360);
FORCEPROP 2 LASTPIN (1525 1300) $PN BW50
J 0
(1535 1310);
DISPLAY 0.617021 (1535 1310);
PAINT ORANGE (1535 1310);
FORCEPROP 2 LASTPIN (1525 1550) $PN H38
J 0
(1535 1560);
DISPLAY 0.617021 (1535 1560);
PAINT ORANGE (1535 1560);
FORCEPROP 2 LASTPIN (1525 1650) $PN H35
J 0
(1535 1660);
DISPLAY 0.617021 (1535 1660);
PAINT ORANGE (1535 1660);
FORCEPROP 2 LASTPIN (1525 1750) $PN G33
J 0
(1535 1760);
DISPLAY 0.617021 (1535 1760);
PAINT ORANGE (1535 1760);
FORCEPROP 2 LASTPIN (1525 1850) $PN H42
J 0
(1535 1860);
DISPLAY 0.617021 (1535 1860);
PAINT ORANGE (1535 1860);
FORCEPROP 2 LASTPIN (1525 1950) $PN C28
J 0
(1535 1960);
DISPLAY 0.617021 (1535 1960);
PAINT ORANGE (1535 1960);
FORCEPROP 2 LASTPIN (1525 1500) $PN K38
J 0
(1535 1510);
DISPLAY 0.617021 (1535 1510);
PAINT ORANGE (1535 1510);
FORCEPROP 2 LASTPIN (1525 1600) $PN K35
J 0
(1535 1610);
DISPLAY 0.617021 (1535 1610);
PAINT ORANGE (1535 1610);
FORCEPROP 2 LASTPIN (1525 1700) $PN J33
J 0
(1535 1710);
DISPLAY 0.617021 (1535 1710);
PAINT ORANGE (1535 1710);
FORCEPROP 2 LASTPIN (1525 1800) $PN K42
J 0
(1535 1810);
DISPLAY 0.617021 (1535 1810);
PAINT ORANGE (1535 1810);
FORCEPROP 2 LASTPIN (1525 1900) $PN A28
J 0
(1535 1910);
DISPLAY 0.617021 (1535 1910);
PAINT ORANGE (1535 1910);
FORCEPROP 2 LASTPIN (1525 2000) $PN J40
J 0
(1535 2010);
DISPLAY 0.617021 (1535 2010);
PAINT ORANGE (1535 2010);
FORCEPROP 2 LASTPIN (1525 2050) $PN G40
J 0
(1535 2060);
DISPLAY 0.617021 (1535 2060);
PAINT ORANGE (1535 2060);
FORCEPROP 2 LASTPIN (1525 2150) $PN B33
J 0
(1535 2160);
DISPLAY 0.617021 (1535 2160);
PAINT ORANGE (1535 2160);
FORCEPROP 2 LASTPIN (1525 2250) $PN K31
J 0
(1535 2260);
DISPLAY 0.617021 (1535 2260);
PAINT ORANGE (1535 2260);
FORCEPROP 2 LASTPIN (1525 2350) $PN B31
J 0
(1535 2360);
DISPLAY 0.617021 (1535 2360);
PAINT ORANGE (1535 2360);
FORCEPROP 2 LASTPIN (1525 2450) $PN G26
J 0
(1535 2460);
DISPLAY 0.617021 (1535 2460);
PAINT ORANGE (1535 2460);
FORCEPROP 2 LASTPIN (1525 2550) $PN D23
J 0
(1535 2560);
DISPLAY 0.617021 (1535 2560);
PAINT ORANGE (1535 2560);
FORCEPROP 2 LASTPIN (1525 2650) $PN D21
J 0
(1535 2660);
DISPLAY 0.617021 (1535 2660);
PAINT ORANGE (1535 2660);
FORCEPROP 2 LASTPIN (1525 2750) $PN H24
J 0
(1535 2760);
DISPLAY 0.617021 (1535 2760);
PAINT ORANGE (1535 2760);
FORCEPROP 2 LASTPIN (1525 2850) $PN A24
J 0
(1535 2860);
DISPLAY 0.617021 (1535 2860);
PAINT ORANGE (1535 2860);
FORCEPROP 2 LASTPIN (1525 2950) $PN A20
J 0
(1535 2960);
DISPLAY 0.617021 (1535 2960);
PAINT ORANGE (1535 2960);
FORCEPROP 2 LASTPIN (1525 2100) $PN D33
J 0
(1535 2110);
DISPLAY 0.617021 (1535 2110);
PAINT ORANGE (1535 2110);
FORCEPROP 2 LASTPIN (1525 2200) $PN H31
J 0
(1535 2210);
DISPLAY 0.617021 (1535 2210);
PAINT ORANGE (1535 2210);
FORCEPROP 2 LASTPIN (1525 2300) $PN D31
J 0
(1535 2310);
DISPLAY 0.617021 (1535 2310);
PAINT ORANGE (1535 2310);
FORCEPROP 2 LASTPIN (1525 2400) $PN J26
J 0
(1535 2410);
DISPLAY 0.617021 (1535 2410);
PAINT ORANGE (1535 2410);
FORCEPROP 2 LASTPIN (1525 2500) $PN B23
J 0
(1535 2510);
DISPLAY 0.617021 (1535 2510);
PAINT ORANGE (1535 2510);
FORCEPROP 2 LASTPIN (1525 2600) $PN B21
J 0
(1535 2610);
DISPLAY 0.617021 (1535 2610);
PAINT ORANGE (1535 2610);
FORCEPROP 2 LASTPIN (1525 2700) $PN K24
J 0
(1535 2710);
DISPLAY 0.617021 (1535 2710);
PAINT ORANGE (1535 2710);
FORCEPROP 2 LASTPIN (1525 2800) $PN C24
J 0
(1535 2810);
DISPLAY 0.617021 (1535 2810);
PAINT ORANGE (1535 2810);
FORCEPROP 2 LASTPIN (1525 2900) $PN C20
J 0
(1535 2910);
DISPLAY 0.617021 (1535 2910);
PAINT ORANGE (1535 2910);
FORCEPROP 2 LASTPIN (1525 3000) $PN K27
J 0
(1535 3010);
DISPLAY 0.617021 (1535 3010);
PAINT ORANGE (1535 3010);
FORCEPROP 2 LASTPIN (1525 3050) $PN H27
J 0
(1535 3060);
DISPLAY 0.617021 (1535 3060);
PAINT ORANGE (1535 3060);
FORCEPROP 0 LAST ROOM SB
J 0
(-825 3700);
DISPLAY 1.361702 (-825 3700);
PAINT ORANGE (-825 3700);
DISPLAY INVISIBLE (-825 3700);
FORCEPROP 2 LAST SEC_TYPE BGA1
J 0
(-375 3375);
DISPLAY 1.021277 (-375 3375);
PAINT ORANGE (-375 3375);
DISPLAY INVISIBLE (-375 3375);
FORCEPROP 2 LAST SEC 1
J 0
(-375 3375);
DISPLAY 0.680851 (-375 3375);
PAINT MONO (-375 3375);
DISPLAY INVISIBLE (-375 3375);
FORCEPROP 0 LAST BOM_COST SB
J 0
(-825 3800);
DISPLAY 1.361702 (-825 3800);
PAINT ORANGE (-825 3800);
DISPLAY INVISIBLE (-825 3800);
FORCEPROP 2 LAST CDS_LOCATION U7C1
J 0
(-380 3332);
DISPLAY 0.617021 (-380 3332);
PAINT AQUA (-380 3332);
DISPLAY INVISIBLE (-380 3332);
FORCEPROP 1 LAST PACK_TYPE BGA1
J 0
(-425 3350);
PAINT SKYBLUE (-425 3350);
DISPLAY INVISIBLE (-425 3350);
FORCEPROP 1 LAST PATH I40
J 0
(525 3250);
PAINT GREEN (525 3250);
DISPLAY INVISIBLE (525 3250);
FORCEPROP 2 LAST CDS_LIB mstr_u_proc
J 0
(525 2150);
PAINT ORANGE (525 2150);
DISPLAY INVISIBLE (525 2150);
FORCEADD OFFPAGE..2
R 2
(-2350 1350);
FORCEPROP 2 LAST $XR0 114 
J 0
(-2605 1350);
DISPLAY 0.638298 (-2605 1350);
PAINT MONO (-2605 1350);
FORCEPROP 1 LAST OFFPAGE TRUE
J 2
(-2675 1225);
DISPLAY 0.872340 (-2675 1225);
PAINT GREEN (-2675 1225);
DISPLAY INVISIBLE (-2675 1225);
FORCEPROP 1 LAST COMMENT_BODY TRUE
J 2
(-2305 1255);
DISPLAY 0.872340 (-2305 1255);
PAINT PEACH (-2305 1255);
DISPLAY INVISIBLE (-2305 1255);
FORCEPROP 2 LAST CDS_LIB mstr_standard
J 0
(-2350 1350);
PAINT ORANGE (-2350 1350);
DISPLAY INVISIBLE (-2350 1350);
FORCEPROP 2 LAST PATH I43
J 0
(-2300 1425);
DISPLAY 1.021277 (-2300 1425);
PAINT ORANGE (-2300 1425);
DISPLAY INVISIBLE (-2300 1425);
FORCEADD OFFPAGE..1
(-2350 1700);
FORCEPROP 2 LAST $XR0 114 
J 0
(-2602 1700);
DISPLAY 0.638298 (-2602 1700);
PAINT MONO (-2602 1700);
FORCEPROP 2 LAST CDS_LIB mstr_standard
J 0
(-2350 1700);
PAINT ORANGE (-2350 1700);
DISPLAY INVISIBLE (-2350 1700);
FORCEPROP 2 LAST PATH I45
J 0
(-2300 1775);
DISPLAY 1.021277 (-2300 1775);
PAINT ORANGE (-2300 1775);
DISPLAY INVISIBLE (-2300 1775);
FORCEPROP 1 LAST COMMENT_BODY TRUE
J 0
(-2225 1600);
DISPLAY 0.872340 (-2225 1600);
PAINT PEACH (-2225 1600);
DISPLAY INVISIBLE (-2225 1600);
FORCEPROP 1 LAST OFFPAGE TRUE
J 0
(-2025 1575);
DISPLAY 0.872340 (-2025 1575);
PAINT GREEN (-2025 1575);
DISPLAY INVISIBLE (-2025 1575);
FORCEADD CAP..1
(225 -225);
FORCEPROP 1 LASTPIN (225 -125) $PN 1
J 0
(235 -145);
DISPLAY 0.617021 (235 -145);
PAINT WHITE (235 -145);
FORCEPROP 1 LASTPIN (225 -325) $PN 2
J 0
(235 -345);
DISPLAY 0.617021 (235 -345);
PAINT WHITE (235 -345);
FORCEPROP 1 LAST MATERIAL C0G
J 0
(275 -325);
DISPLAY 0.617021 (275 -325);
PAINT SKYBLUE (275 -325);
FORCEPROP 1 LAST LOCATION C7C15
J 0
(275 -125);
DISPLAY 0.617021 (275 -125);
PAINT AQUA (275 -125);
FORCEPROP 1 LAST PACK_TYPE 0402LF
J 0
(275 -425);
DISPLAY 0.617021 (275 -425);
PAINT SKYBLUE (275 -425);
FORCEPROP 1 LAST VOLTAGE 50V
J 0
(275 -225);
DISPLAY 0.617021 (275 -225);
PAINT SKYBLUE (275 -225);
FORCEPROP 1 LAST VALUE 18PF
J 0
(275 -175);
DISPLAY 0.617021 (275 -175);
PAINT SKYBLUE (275 -175);
FORCEPROP 1 LAST TOLERANCE 5%
J 0
(275 -275);
DISPLAY 0.617021 (275 -275);
PAINT SKYBLUE (275 -275);
FORCEPROP 1 LAST PART_NUMBER A36095-042
J 0
(275 -375);
DISPLAY 0.617021 (275 -375);
PAINT BLUE (275 -375);
FORCEPROP 2 LAST CDS_LIB mstr_discrete
J 0
(225 -225);
PAINT ORANGE (225 -225);
DISPLAY INVISIBLE (225 -225);
FORCEPROP 2 LAST ROOM SB
J 0
(275 -75);
DISPLAY 1.404255 (275 -75);
PAINT ORANGE (275 -75);
DISPLAY INVISIBLE (275 -75);
FORCEPROP 1 LAST PATH I46
J 0
(275 -75);
DISPLAY 0.978723 (275 -75);
PAINT WHITE (275 -75);
DISPLAY INVISIBLE (275 -75);
FORCEPROP 2 LAST CDS_LOCATION C7C15
J 0
(275 -125);
DISPLAY 0.617021 (275 -125);
PAINT AQUA (275 -125);
DISPLAY INVISIBLE (275 -125);
FORCEPROP 2 LAST $SEC 1
J 0
(275 -25);
DISPLAY 0.936170 (275 -25);
PAINT MONO (275 -25);
DISPLAY INVISIBLE (275 -25);
FORCEPROP 2 LAST CDS_SEC 1
J 0
(275 -25);
DISPLAY 1.404255 (275 -25);
PAINT ORANGE (275 -25);
DISPLAY INVISIBLE (275 -25);
FORCEADD CAP..1
(-1525 -225);
FORCEPROP 1 LAST PACK_TYPE 0402LF
J 0
(-1475 -425);
DISPLAY 0.617021 (-1475 -425);
PAINT SKYBLUE (-1475 -425);
FORCEPROP 1 LAST MATERIAL COG
J 0
(-1475 -325);
DISPLAY 0.617021 (-1475 -325);
PAINT SKYBLUE (-1475 -325);
FORCEPROP 1 LASTPIN (-1525 -325) $PN 2
J 0
(-1515 -345);
DISPLAY 0.617021 (-1515 -345);
PAINT ORANGE (-1515 -345);
FORCEPROP 1 LAST TOLERANCE 5%
J 0
(-1475 -275);
DISPLAY 0.617021 (-1475 -275);
PAINT SKYBLUE (-1475 -275);
FORCEPROP 1 LASTPIN (-1525 -125) $PN 1
J 0
(-1515 -145);
DISPLAY 0.617021 (-1515 -145);
PAINT ORANGE (-1515 -145);
FORCEPROP 1 LAST VOLTAGE 50V
J 0
(-1475 -225);
DISPLAY 0.617021 (-1475 -225);
PAINT SKYBLUE (-1475 -225);
FORCEPROP 1 LAST VALUE 15.0PF
J 0
(-1475 -175);
DISPLAY 0.617021 (-1475 -175);
PAINT SKYBLUE (-1475 -175);
FORCEPROP 1 LAST LOCATION C7C5
J 0
(-1475 -125);
DISPLAY 0.617021 (-1475 -125);
PAINT AQUA (-1475 -125);
FORCEPROP 1 LAST PART_NUMBER A36095-047
J 0
(-1475 -375);
DISPLAY 0.617021 (-1475 -375);
PAINT BLUE (-1475 -375);
FORCEPROP 2 LAST CDS_LOCATION C7C5
J 0
(-1475 -125);
DISPLAY 0.617021 (-1475 -125);
PAINT AQUA (-1475 -125);
DISPLAY INVISIBLE (-1475 -125);
FORCEPROP 1 LAST PATH I47
J 0
(-1475 -75);
DISPLAY 0.978723 (-1475 -75);
PAINT WHITE (-1475 -75);
DISPLAY INVISIBLE (-1475 -75);
FORCEPROP 2 LAST BOM_COST SYS_CLOCK
J 0
(-1435 -115);
PAINT MONO (-1435 -115);
DISPLAY INVISIBLE (-1435 -115);
FORCEPROP 2 LAST CDS_LIB mstr_discrete
J 0
(-1525 -225);
PAINT ORANGE (-1525 -225);
DISPLAY INVISIBLE (-1525 -225);
FORCEPROP 2 LAST ROOM SB
J 0
(-1525 -225);
PAINT MONO (-1525 -225);
DISPLAY INVISIBLE (-1525 -225);
FORCEPROP 2 LAST SEC 1
J 0
(-1475 -25);
DISPLAY 0.680851 (-1475 -25);
PAINT MONO (-1475 -25);
DISPLAY INVISIBLE (-1475 -25);
FORCEPROP 2 LAST SEC_TYPE 0402LF
J 0
(-1475 -25);
DISPLAY 1.021277 (-1475 -25);
PAINT ORANGE (-1475 -25);
DISPLAY INVISIBLE (-1475 -25);
FORCEADD RES..1
(-1775 475);
FORCEPROP 1 LAST LOCATION R7C1
J 0
(-1825 525);
DISPLAY 0.617021 (-1825 525);
PAINT AQUA (-1825 525);
FORCEPROP 1 LAST VALUE 200K
J 2
(-1800 375);
DISPLAY 0.617021 (-1800 375);
PAINT SKYBLUE (-1800 375);
FORCEPROP 1 LAST WATTAGE 1/10W
J 2
(-1800 325);
DISPLAY 0.617021 (-1800 325);
PAINT SKYBLUE (-1800 325);
FORCEPROP 1 LAST MATERIAL CHIP
J 0
(-1775 325);
DISPLAY 0.617021 (-1775 325);
PAINT SKYBLUE (-1775 325);
FORCEPROP 1 LAST TOLERANCE 0.1%
J 0
(-1775 375);
DISPLAY 0.617021 (-1775 375);
PAINT SKYBLUE (-1775 375);
FORCEPROP 1 LASTPIN (-1875 475) $PN 1
J 0
(-1863 487);
DISPLAY 0.617021 (-1863 487);
PAINT ORANGE (-1863 487);
FORCEPROP 1 LASTPIN (-1675 475) $PN 2
J 0
(-1713 487);
DISPLAY 0.617021 (-1713 487);
PAINT ORANGE (-1713 487);
FORCEPROP 1 LAST PACK_TYPE 0603
J 0
(-1650 375);
DISPLAY 0.617021 (-1650 375);
PAINT SKYBLUE (-1650 375);
FORCEPROP 1 LAST PART_NUMBER G22369-010
J 0
(-1825 575);
DISPLAY 0.617021 (-1825 575);
PAINT BLUE (-1825 575);
FORCEPROP 2 LAST ROOM SB
J 0
(-1775 475);
PAINT MONO (-1775 475);
DISPLAY INVISIBLE (-1775 475);
FORCEPROP 2 LAST CDS_LIB mstr_discrete
J 0
(-1775 475);
PAINT ORANGE (-1775 475);
DISPLAY INVISIBLE (-1775 475);
FORCEPROP 1 LAST PATH I48
J 0
(-1825 625);
DISPLAY 0.978723 (-1825 625);
PAINT WHITE (-1825 625);
DISPLAY INVISIBLE (-1825 625);
FORCEPROP 2 LAST CDS_LOCATION R7C1
J 0
(-1825 525);
DISPLAY 0.617021 (-1825 525);
PAINT AQUA (-1825 525);
DISPLAY INVISIBLE (-1825 525);
FORCEPROP 2 LAST SEC 1
J 0
(-1825 675);
DISPLAY 0.680851 (-1825 675);
PAINT MONO (-1825 675);
DISPLAY INVISIBLE (-1825 675);
FORCEPROP 2 LAST SEC_TYPE 0603
J 0
(-1825 675);
DISPLAY 1.021277 (-1825 675);
PAINT ORANGE (-1825 675);
DISPLAY INVISIBLE (-1825 675);
FORCEADD CRYSTAL..1
(-1775 125);
FORCEPROP 1 LAST PART_NUMBER D71700-058
J 0
(-1975 -25);
DISPLAY 0.617021 (-1975 -25);
PAINT BLUE (-1975 -25);
FORCEPROP 1 LASTPIN (-1875 125) $PN 1
J 2
(-1830 135);
DISPLAY 0.617021 (-1830 135);
PAINT AQUA (-1830 135);
FORCEPROP 1 LAST VALUE 48.000MHZ
J 1
(-1768 186);
DISPLAY 0.617021 (-1768 186);
PAINT SKYBLUE (-1768 186);
FORCEPROP 1 LAST LOCATION Y7C1
J 1
(-1770 224);
DISPLAY 0.617021 (-1770 224);
PAINT AQUA (-1770 224);
FORCEPROP 1 LASTPIN (-1675 125) $PN 3
J 0
(-1710 135);
DISPLAY 0.617021 (-1710 135);
PAINT AQUA (-1710 135);
FORCEPROP 1 LAST MATERIAL IC
J 0
(-1786 41);
DISPLAY 0.617021 (-1786 41);
PAINT SKYBLUE (-1786 41);
FORCEPROP 2 LAST CDS_LIB mstr_discrete
J 0
(-1775 125);
PAINT ORANGE (-1775 125);
DISPLAY INVISIBLE (-1775 125);
FORCEPROP 1 LAST PACK_TYPE 2013
J 0
(-1787 33);
DISPLAY 0.702128 (-1787 33);
PAINT SKYBLUE (-1787 33);
DISPLAY INVISIBLE (-1787 33);
FORCEPROP 2 LAST CDS_LOCATION Y7C1
J 1
(-1770 224);
DISPLAY 0.617021 (-1770 224);
PAINT AQUA (-1770 224);
DISPLAY INVISIBLE (-1770 224);
FORCEPROP 1 LAST PATH I49
J 0
(-1750 225);
DISPLAY 0.872340 (-1750 225);
PAINT PINK (-1750 225);
DISPLAY INVISIBLE (-1750 225);
FORCEPROP 2 LAST SEC_TYPE 2013
J 0
(-1750 275);
DISPLAY 1.021277 (-1750 275);
PAINT ORANGE (-1750 275);
DISPLAY INVISIBLE (-1750 275);
FORCEPROP 2 LAST SEC 1
J 0
(-1750 275);
PAINT MONO (-1750 275);
DISPLAY INVISIBLE (-1750 275);
FORCEPROP 0 LAST ROOM SB
J 0
(-1750 325);
DISPLAY 1.404255 (-1750 325);
PAINT ORANGE (-1750 325);
DISPLAY INVISIBLE (-1750 325);
FORCEADD CAP..1
(-2025 -225);
FORCEPROP 1 LASTPIN (-2025 -325) $PN 2
J 0
(-2015 -345);
DISPLAY 0.617021 (-2015 -345);
PAINT ORANGE (-2015 -345);
FORCEPROP 1 LAST MATERIAL COG
J 0
(-1975 -325);
DISPLAY 0.617021 (-1975 -325);
PAINT SKYBLUE (-1975 -325);
FORCEPROP 1 LAST PACK_TYPE 0402LF
J 0
(-1975 -425);
DISPLAY 0.617021 (-1975 -425);
PAINT SKYBLUE (-1975 -425);
FORCEPROP 1 LAST TOLERANCE 5%
J 0
(-1975 -275);
DISPLAY 0.617021 (-1975 -275);
PAINT SKYBLUE (-1975 -275);
FORCEPROP 1 LASTPIN (-2025 -125) $PN 1
J 0
(-2015 -145);
DISPLAY 0.617021 (-2015 -145);
PAINT ORANGE (-2015 -145);
FORCEPROP 1 LAST VOLTAGE 50V
J 0
(-1975 -225);
DISPLAY 0.617021 (-1975 -225);
PAINT SKYBLUE (-1975 -225);
FORCEPROP 1 LAST VALUE 15.0PF
J 0
(-1975 -175);
DISPLAY 0.617021 (-1975 -175);
PAINT SKYBLUE (-1975 -175);
FORCEPROP 1 LAST LOCATION C7C4
J 0
(-1975 -125);
DISPLAY 0.617021 (-1975 -125);
PAINT AQUA (-1975 -125);
FORCEPROP 1 LAST PART_NUMBER A36095-047
J 0
(-1975 -375);
DISPLAY 0.617021 (-1975 -375);
PAINT BLUE (-1975 -375);
FORCEPROP 2 LAST BOM_COST SYS_CLOCK
J 0
(-1885 -415);
PAINT MONO (-1885 -415);
DISPLAY INVISIBLE (-1885 -415);
FORCEPROP 2 LAST ROOM SB
J 0
(-2025 -225);
PAINT MONO (-2025 -225);
DISPLAY INVISIBLE (-2025 -225);
FORCEPROP 1 LAST PATH I50
J 0
(-1975 -75);
DISPLAY 0.978723 (-1975 -75);
PAINT WHITE (-1975 -75);
DISPLAY INVISIBLE (-1975 -75);
FORCEPROP 2 LAST CDS_LOCATION C7C4
J 0
(-1975 -125);
DISPLAY 0.617021 (-1975 -125);
PAINT AQUA (-1975 -125);
DISPLAY INVISIBLE (-1975 -125);
FORCEPROP 2 LAST CDS_LIB mstr_discrete
J 0
(-2025 -225);
PAINT ORANGE (-2025 -225);
DISPLAY INVISIBLE (-2025 -225);
FORCEPROP 2 LAST SEC 1
J 0
(-1975 -25);
DISPLAY 0.680851 (-1975 -25);
PAINT MONO (-1975 -25);
DISPLAY INVISIBLE (-1975 -25);
FORCEPROP 2 LAST SEC_TYPE 0402LF
J 0
(-1975 -25);
DISPLAY 1.021277 (-1975 -25);
PAINT ORANGE (-1975 -25);
DISPLAY INVISIBLE (-1975 -25);
FORCEADD OFFPAGE..5
(-2575 625);
FORCEPROP 2 LAST $XR0 114 
J 0
(-2830 625);
DISPLAY 0.638298 (-2830 625);
PAINT MONO (-2830 625);
FORCEPROP 2 LAST BOM_COST SYS_CLOCK
J 0
(-2825 675);
PAINT MONO (-2825 675);
DISPLAY INVISIBLE (-2825 675);
FORCEPROP 2 LAST CDS_LIB mstr_standard
J 0
(-2575 625);
PAINT MONO (-2575 625);
DISPLAY INVISIBLE (-2575 625);
FORCEPROP 2 LAST PATH I51
J 0
(-2525 700);
DISPLAY 1.021277 (-2525 700);
PAINT ORANGE (-2525 700);
DISPLAY INVISIBLE (-2525 700);
FORCEPROP 1 LAST COMMENT_BODY TRUE
J 0
(-2475 545);
DISPLAY 1.148936 (-2475 545);
PAINT PEACH (-2475 545);
DISPLAY INVISIBLE (-2475 545);
FORCEPROP 1 LAST OFFPAGE TRUE
J 0
(-2255 495);
PAINT GREEN (-2255 495);
DISPLAY INVISIBLE (-2255 495);
FORCEADD GND..1
(-2025 -575);
FORCEPROP 3 LASTPIN (-2025 -525) SIG_NAME GND\g
J 0
(-2015 -515);
DISPLAY 0.659574 (-2015 -515);
PAINT MONO (-2015 -515);
DISPLAY INVISIBLE (-2015 -515);
FORCEPROP 1 LAST BODY_TYPE PLUMBING
J 0
(-2070 -618);
DISPLAY 0.340426 (-2070 -618);
PAINT GREEN (-2070 -618);
DISPLAY INVISIBLE (-2070 -618);
FORCEPROP 2 LAST BOM_COST SYS_CLOCK
J 0
(-2325 -500);
PAINT MONO (-2325 -500);
DISPLAY INVISIBLE (-2325 -500);
FORCEPROP 1 LAST PATH I53
J 0
(-1950 -575);
DISPLAY 0.872340 (-1950 -575);
PAINT AQUA (-1950 -575);
DISPLAY INVISIBLE (-1950 -575);
FORCEPROP 1 LAST VOLTAGE 0
J 0
(-2025 -575);
DISPLAY 0.510638 (-2025 -575);
PAINT SKYBLUE (-2025 -575);
DISPLAY INVISIBLE (-2025 -575);
FORCEPROP 1 LAST SIZE 1B
J 0
(-1950 -625);
DISPLAY 0.872340 (-1950 -625);
PAINT GREEN (-1950 -625);
DISPLAY INVISIBLE (-1950 -625);
FORCEPROP 2 LAST CDS_LIB mstr_symbols
J 0
(-2025 -575);
PAINT ORANGE (-2025 -575);
DISPLAY INVISIBLE (-2025 -575);
FORCEPROP 1 LAST HDL_POWER GND
J 0
(-2025 -425);
DISPLAY 0.702128 (-2025 -425);
PAINT GREEN (-2025 -425);
DISPLAY INVISIBLE (-2025 -425);
FORCEADD RES..1
(-25 475);
FORCEPROP 1 LAST PACK_TYPE 0603
J 0
(75 420);
DISPLAY 0.617021 (75 420);
PAINT SKYBLUE (75 420);
FORCEPROP 1 LASTPIN (-125 475) $PN 1
J 0
(-115 485);
DISPLAY 0.617021 (-115 485);
PAINT WHITE (-115 485);
FORCEPROP 1 LAST MATERIAL CHIP
J 0
(-205 370);
DISPLAY 0.617021 (-205 370);
PAINT SKYBLUE (-205 370);
FORCEPROP 1 LAST VALUE 10M
J 2
(-105 420);
DISPLAY 0.617021 (-105 420);
PAINT SKYBLUE (-105 420);
FORCEPROP 1 LAST WATTAGE 1/10W
J 2
(70 375);
DISPLAY 0.617021 (70 375);
PAINT SKYBLUE (70 375);
FORCEPROP 1 LAST TOLERANCE 1.0%
J 0
(-25 420);
DISPLAY 0.617021 (-25 420);
PAINT SKYBLUE (-25 420);
FORCEPROP 1 LAST PART_NUMBER G22026-112
J 0
(-125 575);
DISPLAY 0.617021 (-125 575);
PAINT BLUE (-125 575);
FORCEPROP 1 LAST LOCATION R7C6
J 0
(-75 525);
DISPLAY 0.617021 (-75 525);
PAINT AQUA (-75 525);
FORCEPROP 1 LASTPIN (75 475) $PN 2
J 0
(35 485);
DISPLAY 0.617021 (35 485);
PAINT WHITE (35 485);
FORCEPROP 2 LAST BOM_COST SYS_CLOCK
J 0
(-75 275);
PAINT MONO (-75 275);
DISPLAY INVISIBLE (-75 275);
FORCEPROP 2 LAST ROOM SB
J 0
(-25 475);
PAINT MONO (-25 475);
DISPLAY INVISIBLE (-25 475);
FORCEPROP 2 LAST CDS_LIB mstr_discrete
J 0
(-25 475);
DISPLAY 1.680851 (-25 475);
PAINT ORANGE (-25 475);
DISPLAY INVISIBLE (-25 475);
FORCEPROP 1 LAST PATH I54
J 0
(-75 625);
DISPLAY 0.978723 (-75 625);
PAINT WHITE (-75 625);
DISPLAY INVISIBLE (-75 625);
FORCEPROP 2 LAST CDS_LOCATION R7C6
J 0
(-75 525);
DISPLAY 0.617021 (-75 525);
PAINT AQUA (-75 525);
DISPLAY INVISIBLE (-75 525);
FORCEPROP 2 LAST $SEC 1
J 0
(-75 675);
DISPLAY 0.936170 (-75 675);
PAINT MONO (-75 675);
DISPLAY INVISIBLE (-75 675);
FORCEPROP 2 LAST CDS_SEC 1
J 0
(-75 675);
DISPLAY 1.404255 (-75 675);
PAINT ORANGE (-75 675);
DISPLAY INVISIBLE (-75 675);
FORCEADD CRYSTAL..1
(-25 125);
FORCEPROP 1 LASTPIN (-125 125) $PN 1
J 2
(-80 135);
DISPLAY 0.617021 (-80 135);
PAINT AQUA (-80 135);
FORCEPROP 1 LAST MATERIAL IC
J 0
(-36 41);
DISPLAY 0.617021 (-36 41);
PAINT SKYBLUE (-36 41);
FORCEPROP 1 LAST VALUE 32.768KHZ
J 1
(-18 186);
DISPLAY 0.617021 (-18 186);
PAINT SKYBLUE (-18 186);
FORCEPROP 1 LAST PART_NUMBER C13544-023
J 0
(-200 -25);
DISPLAY 0.617021 (-200 -25);
PAINT BLUE (-200 -25);
FORCEPROP 1 LAST LOCATION Y7C2
J 1
(-20 224);
DISPLAY 0.617021 (-20 224);
PAINT AQUA (-20 224);
FORCEPROP 1 LASTPIN (75 125) $PN 2
J 0
(40 135);
DISPLAY 0.617021 (40 135);
PAINT AQUA (40 135);
FORCEPROP 1 LAST PACK_TYPE SM
J 0
(-37 33);
DISPLAY 0.702128 (-37 33);
PAINT SKYBLUE (-37 33);
DISPLAY INVISIBLE (-37 33);
FORCEPROP 2 LAST CDS_LIB mstr_discrete
J 0
(-25 125);
PAINT ORANGE (-25 125);
DISPLAY INVISIBLE (-25 125);
FORCEPROP 2 LAST CDS_LOCATION Y7C2
J 1
(-20 224);
DISPLAY 0.617021 (-20 224);
PAINT AQUA (-20 224);
DISPLAY INVISIBLE (-20 224);
FORCEPROP 2 LAST ROOM SB
J 0
(0 350);
DISPLAY 1.404255 (0 350);
PAINT ORANGE (0 350);
DISPLAY INVISIBLE (0 350);
FORCEPROP 1 LAST PATH I55
J 0
(0 225);
DISPLAY 0.872340 (0 225);
PAINT PINK (0 225);
DISPLAY INVISIBLE (0 225);
FORCEPROP 2 LAST SEC 1
J 0
(0 275);
PAINT MONO (0 275);
DISPLAY INVISIBLE (0 275);
FORCEPROP 2 LAST SEC_TYPE SM
J 0
(0 275);
DISPLAY 1.021277 (0 275);
PAINT ORANGE (0 275);
DISPLAY INVISIBLE (0 275);
FORCEADD CAP..1
(-275 -225);
FORCEPROP 1 LASTPIN (-275 -125) $PN 1
J 0
(-265 -145);
DISPLAY 0.617021 (-265 -145);
PAINT WHITE (-265 -145);
FORCEPROP 1 LASTPIN (-275 -325) $PN 2
J 0
(-265 -345);
DISPLAY 0.617021 (-265 -345);
PAINT WHITE (-265 -345);
FORCEPROP 1 LAST MATERIAL C0G
J 0
(-225 -325);
DISPLAY 0.617021 (-225 -325);
PAINT SKYBLUE (-225 -325);
FORCEPROP 1 LAST VOLTAGE 50V
J 0
(-225 -225);
DISPLAY 0.617021 (-225 -225);
PAINT SKYBLUE (-225 -225);
FORCEPROP 1 LAST LOCATION C7C13
J 0
(-225 -125);
DISPLAY 0.617021 (-225 -125);
PAINT AQUA (-225 -125);
FORCEPROP 1 LAST VALUE 18PF
J 0
(-225 -175);
DISPLAY 0.617021 (-225 -175);
PAINT SKYBLUE (-225 -175);
FORCEPROP 1 LAST TOLERANCE 5%
J 0
(-225 -275);
DISPLAY 0.617021 (-225 -275);
PAINT SKYBLUE (-225 -275);
FORCEPROP 1 LAST PACK_TYPE 0402LF
J 0
(-225 -425);
DISPLAY 0.617021 (-225 -425);
PAINT SKYBLUE (-225 -425);
FORCEPROP 1 LAST PART_NUMBER A36095-042
J 0
(-225 -375);
DISPLAY 0.617021 (-225 -375);
PAINT BLUE (-225 -375);
FORCEPROP 2 LAST CDS_LIB mstr_discrete
J 0
(-275 -225);
PAINT ORANGE (-275 -225);
DISPLAY INVISIBLE (-275 -225);
FORCEPROP 2 LAST CDS_LOCATION C7C13
J 0
(-225 -125);
DISPLAY 0.617021 (-225 -125);
PAINT AQUA (-225 -125);
DISPLAY INVISIBLE (-225 -125);
FORCEPROP 1 LAST PATH I56
J 0
(-225 -75);
DISPLAY 0.978723 (-225 -75);
PAINT WHITE (-225 -75);
DISPLAY INVISIBLE (-225 -75);
FORCEPROP 2 LAST ROOM SB
J 0
(-225 -75);
DISPLAY 1.404255 (-225 -75);
PAINT ORANGE (-225 -75);
DISPLAY INVISIBLE (-225 -75);
FORCEPROP 2 LAST $SEC 1
J 0
(-225 -25);
DISPLAY 0.936170 (-225 -25);
PAINT MONO (-225 -25);
DISPLAY INVISIBLE (-225 -25);
FORCEPROP 2 LAST CDS_SEC 1
J 0
(-225 -25);
DISPLAY 1.404255 (-225 -25);
PAINT ORANGE (-225 -25);
DISPLAY INVISIBLE (-225 -25);
FORCEADD GND..1
(-275 -575);
FORCEPROP 3 LASTPIN (-275 -525) SIG_NAME GND\g
J 0
(-265 -515);
DISPLAY 0.659574 (-265 -515);
PAINT MONO (-265 -515);
DISPLAY INVISIBLE (-265 -515);
FORCEPROP 2 LAST BOM_COST SYS_CLOCK
J 0
(-575 -500);
PAINT MONO (-575 -500);
DISPLAY INVISIBLE (-575 -500);
FORCEPROP 1 LAST PATH I57
J 0
(-200 -575);
DISPLAY 0.872340 (-200 -575);
PAINT AQUA (-200 -575);
DISPLAY INVISIBLE (-200 -575);
FORCEPROP 1 LAST BODY_TYPE PLUMBING
J 0
(-320 -618);
DISPLAY 0.340426 (-320 -618);
PAINT GREEN (-320 -618);
DISPLAY INVISIBLE (-320 -618);
FORCEPROP 2 LAST CDS_LIB mstr_symbols
J 0
(-275 -575);
PAINT ORANGE (-275 -575);
DISPLAY INVISIBLE (-275 -575);
FORCEPROP 1 LAST SIZE 1B
J 0
(-200 -625);
DISPLAY 0.872340 (-200 -625);
PAINT GREEN (-200 -625);
DISPLAY INVISIBLE (-200 -625);
FORCEPROP 1 LAST VOLTAGE 0
J 0
(-275 -575);
DISPLAY 0.510638 (-275 -575);
PAINT SKYBLUE (-275 -575);
DISPLAY INVISIBLE (-275 -575);
FORCEPROP 1 LAST HDL_POWER GND
J 0
(-275 -425);
DISPLAY 0.702128 (-275 -425);
PAINT GREEN (-275 -425);
DISPLAY INVISIBLE (-275 -425);
FORCEADD OFFPAGE..4
R 2
(-925 725);
FORCEPROP 2 LAST $XR0 114 
J 0
(-1177 725);
DISPLAY 0.638298 (-1177 725);
PAINT MONO (-1177 725);
FORCEPROP 1 LAST OFFPAGE TRUE
J 2
(-1250 600);
PAINT GREEN (-1250 600);
DISPLAY INVISIBLE (-1250 600);
FORCEPROP 2 LAST BOM_COST SYS_CLOCK
J 0
(-1200 775);
PAINT MONO (-1200 775);
DISPLAY INVISIBLE (-1200 775);
FORCEPROP 1 LAST COMMENT_BODY TRUE
J 2
(-900 625);
DISPLAY 1.212766 (-900 625);
PAINT PEACH (-900 625);
DISPLAY INVISIBLE (-900 625);
FORCEPROP 2 LAST CDS_LIB mstr_standard
J 0
(-925 725);
PAINT ORANGE (-925 725);
DISPLAY INVISIBLE (-925 725);
FORCEPROP 2 LAST PATH I58
J 0
(-875 800);
DISPLAY 1.021277 (-875 800);
PAINT ORANGE (-875 800);
DISPLAY INVISIBLE (-875 800);
FORCEADD OFFPAGE..5
(-925 625);
FORCEPROP 2 LAST $XR0 114 
J 0
(-1180 625);
DISPLAY 0.638298 (-1180 625);
PAINT MONO (-1180 625);
FORCEPROP 2 LAST BOM_COST SYS_CLOCK
J 0
(-1175 675);
PAINT MONO (-1175 675);
DISPLAY INVISIBLE (-1175 675);
FORCEPROP 1 LAST OFFPAGE TRUE
J 0
(-605 495);
PAINT GREEN (-605 495);
DISPLAY INVISIBLE (-605 495);
FORCEPROP 2 LAST CDS_LIB mstr_standard
J 0
(-925 625);
PAINT ORANGE (-925 625);
DISPLAY INVISIBLE (-925 625);
FORCEPROP 2 LAST PATH I59
J 0
(-875 700);
DISPLAY 1.021277 (-875 700);
PAINT ORANGE (-875 700);
DISPLAY INVISIBLE (-875 700);
FORCEPROP 1 LAST COMMENT_BODY TRUE
J 0
(-825 545);
DISPLAY 1.148936 (-825 545);
PAINT PEACH (-825 545);
DISPLAY INVISIBLE (-825 545);
FORCEADD OFFPAGE..4
R 2
(-2575 725);
FORCEPROP 2 LAST $XR0 114 
J 0
(-2827 725);
DISPLAY 0.638298 (-2827 725);
PAINT MONO (-2827 725);
FORCEPROP 1 LAST OFFPAGE TRUE
J 2
(-2900 600);
PAINT GREEN (-2900 600);
DISPLAY INVISIBLE (-2900 600);
FORCEPROP 2 LAST BOM_COST SYS_CLOCK
J 0
(-2850 775);
PAINT MONO (-2850 775);
DISPLAY INVISIBLE (-2850 775);
FORCEPROP 2 LAST CDS_LIB mstr_standard
J 0
(-2575 725);
PAINT MONO (-2575 725);
DISPLAY INVISIBLE (-2575 725);
FORCEPROP 2 LAST PATH I60
J 0
(-2525 800);
DISPLAY 1.021277 (-2525 800);
PAINT ORANGE (-2525 800);
DISPLAY INVISIBLE (-2525 800);
FORCEPROP 1 LAST COMMENT_BODY TRUE
J 2
(-2550 625);
DISPLAY 1.212766 (-2550 625);
PAINT PEACH (-2550 625);
DISPLAY INVISIBLE (-2550 625);
FORCEADD OFFPAGE..2
(3700 1350);
FORCEPROP 2 LAST $XR0 21 
J 0
(3889 1350);
DISPLAY 0.638298 (3889 1350);
PAINT MONO (3889 1350);
FORCEPROP 2 LAST $XR1 55 
J 0
(3979 1350);
DISPLAY 0.638298 (3979 1350);
PAINT MONO (3979 1350);
FORCEPROP 1 LAST COMMENT_BODY TRUE
J 0
(3655 1255);
DISPLAY 0.872340 (3655 1255);
PAINT PEACH (3655 1255);
DISPLAY INVISIBLE (3655 1255);
FORCEPROP 2 LAST CDS_LIB mstr_standard
J 0
(3700 1350);
PAINT ORANGE (3700 1350);
DISPLAY INVISIBLE (3700 1350);
FORCEPROP 2 LAST PATH I62
J 0
(3875 1425);
DISPLAY 1.021277 (3875 1425);
PAINT ORANGE (3875 1425);
DISPLAY INVISIBLE (3875 1425);
FORCEPROP 1 LAST OFFPAGE TRUE
J 0
(4025 1225);
DISPLAY 0.872340 (4025 1225);
PAINT GREEN (4025 1225);
DISPLAY INVISIBLE (4025 1225);
FORCEADD OFFPAGE..2
(3700 550);
FORCEPROP 2 LAST $XR0 144 
J 0
(3889 550);
DISPLAY 0.638298 (3889 550);
PAINT MONO (3889 550);
FORCEPROP 2 LASTPIN (3650 550) SIG_NAME CLK_48M_USB_BMC
J 2
(3640 560);
DISPLAY 0.617021 (3640 560);
PAINT ORANGE (3640 560);
FORCEPROP 1 LAST COMMENT_BODY TRUE
J 0
(3655 455);
DISPLAY 0.872340 (3655 455);
PAINT PEACH (3655 455);
DISPLAY INVISIBLE (3655 455);
FORCEPROP 1 LAST OFFPAGE TRUE
J 0
(4025 425);
DISPLAY 0.872340 (4025 425);
PAINT GREEN (4025 425);
DISPLAY INVISIBLE (4025 425);
FORCEPROP 2 LAST CDS_LIB mstr_standard
J 0
(3700 550);
PAINT ORANGE (3700 550);
DISPLAY INVISIBLE (3700 550);
FORCEPROP 2 LAST PATH I63
J 0
(3875 625);
DISPLAY 1.021277 (3875 625);
PAINT ORANGE (3875 625);
DISPLAY INVISIBLE (3875 625);
FORCEADD OFFPAGE..2
R 2
(-2350 1900);
FORCEPROP 2 LAST $XR0 114 
J 0
(-2605 1900);
DISPLAY 0.638298 (-2605 1900);
PAINT MONO (-2605 1900);
FORCEPROP 1 LAST OFFPAGE TRUE
J 2
(-2675 1775);
DISPLAY 0.872340 (-2675 1775);
PAINT GREEN (-2675 1775);
DISPLAY INVISIBLE (-2675 1775);
FORCEPROP 1 LAST COMMENT_BODY TRUE
J 2
(-2305 1805);
DISPLAY 0.872340 (-2305 1805);
PAINT PEACH (-2305 1805);
DISPLAY INVISIBLE (-2305 1805);
FORCEPROP 2 LAST CDS_LIB mstr_standard
J 0
(-2350 1900);
PAINT ORANGE (-2350 1900);
DISPLAY INVISIBLE (-2350 1900);
FORCEPROP 2 LAST PATH I64
J 0
(-2300 1975);
DISPLAY 1.021277 (-2300 1975);
PAINT ORANGE (-2300 1975);
DISPLAY INVISIBLE (-2300 1975);
FORCEADD OFFPAGE..2
(3700 1850);
FORCEPROP 2 LAST $XR0 108 
J 0
(3889 1850);
DISPLAY 0.638298 (3889 1850);
PAINT MONO (3889 1850);
FORCEPROP 1 LAST COMMENT_BODY TRUE
J 0
(3655 1755);
DISPLAY 0.872340 (3655 1755);
PAINT PEACH (3655 1755);
DISPLAY INVISIBLE (3655 1755);
FORCEPROP 2 LAST CDS_LIB mstr_standard
J 0
(3700 1850);
PAINT ORANGE (3700 1850);
DISPLAY INVISIBLE (3700 1850);
FORCEPROP 1 LAST OFFPAGE TRUE
J 0
(4025 1725);
DISPLAY 0.872340 (4025 1725);
PAINT GREEN (4025 1725);
DISPLAY INVISIBLE (4025 1725);
FORCEPROP 2 LAST PATH I89
J 0
(3875 1925);
DISPLAY 1.021277 (3875 1925);
PAINT ORANGE (3875 1925);
DISPLAY INVISIBLE (3875 1925);
FORCEADD OFFPAGE..2
(3700 1800);
FORCEPROP 2 LAST $XR0 108 
J 0
(3889 1800);
DISPLAY 0.638298 (3889 1800);
PAINT MONO (3889 1800);
FORCEPROP 1 LAST COMMENT_BODY TRUE
J 0
(3655 1705);
DISPLAY 0.872340 (3655 1705);
PAINT PEACH (3655 1705);
DISPLAY INVISIBLE (3655 1705);
FORCEPROP 2 LAST CDS_LIB mstr_standard
J 0
(3700 1800);
PAINT ORANGE (3700 1800);
DISPLAY INVISIBLE (3700 1800);
FORCEPROP 1 LAST OFFPAGE TRUE
J 0
(4025 1675);
DISPLAY 0.872340 (4025 1675);
PAINT GREEN (4025 1675);
DISPLAY INVISIBLE (4025 1675);
FORCEPROP 2 LAST PATH I90
J 0
(3875 1875);
DISPLAY 1.021277 (3875 1875);
PAINT ORANGE (3875 1875);
DISPLAY INVISIBLE (3875 1875);
FORCEADD OFFPAGE..2
(3700 2050);
FORCEPROP 2 LAST $XR0 108 
J 0
(3889 2050);
DISPLAY 0.638298 (3889 2050);
PAINT MONO (3889 2050);
FORCEPROP 1 LAST COMMENT_BODY TRUE
J 0
(3655 1955);
DISPLAY 0.872340 (3655 1955);
PAINT PEACH (3655 1955);
DISPLAY INVISIBLE (3655 1955);
FORCEPROP 1 LAST OFFPAGE TRUE
J 0
(4025 1925);
DISPLAY 0.872340 (4025 1925);
PAINT GREEN (4025 1925);
DISPLAY INVISIBLE (4025 1925);
FORCEPROP 2 LAST CDS_LIB mstr_standard
J 0
(3700 2050);
PAINT ORANGE (3700 2050);
DISPLAY INVISIBLE (3700 2050);
FORCEPROP 2 LAST PATH I93
J 0
(3875 2125);
DISPLAY 1.021277 (3875 2125);
PAINT ORANGE (3875 2125);
DISPLAY INVISIBLE (3875 2125);
FORCEADD OFFPAGE..2
(3700 2000);
FORCEPROP 2 LAST $XR0 108 
J 0
(3889 2000);
DISPLAY 0.638298 (3889 2000);
PAINT MONO (3889 2000);
FORCEPROP 1 LAST COMMENT_BODY TRUE
J 0
(3655 1905);
DISPLAY 0.872340 (3655 1905);
PAINT PEACH (3655 1905);
DISPLAY INVISIBLE (3655 1905);
FORCEPROP 2 LAST CDS_LIB mstr_standard
J 0
(3700 2000);
PAINT ORANGE (3700 2000);
DISPLAY INVISIBLE (3700 2000);
FORCEPROP 1 LAST OFFPAGE TRUE
J 0
(4025 1875);
DISPLAY 0.872340 (4025 1875);
PAINT GREEN (4025 1875);
DISPLAY INVISIBLE (4025 1875);
FORCEPROP 2 LAST PATH I94
J 0
(3875 2075);
DISPLAY 1.021277 (3875 2075);
PAINT ORANGE (3875 2075);
DISPLAY INVISIBLE (3875 2075);
FORCEADD OFFPAGE..2
(3700 2150);
FORCEPROP 2 LAST $XR0 108 
J 0
(3889 2150);
DISPLAY 0.638298 (3889 2150);
PAINT MONO (3889 2150);
FORCEPROP 1 LAST OFFPAGE TRUE
J 0
(4025 2025);
DISPLAY 0.872340 (4025 2025);
PAINT GREEN (4025 2025);
DISPLAY INVISIBLE (4025 2025);
FORCEPROP 1 LAST COMMENT_BODY TRUE
J 0
(3655 2055);
DISPLAY 0.872340 (3655 2055);
PAINT PEACH (3655 2055);
DISPLAY INVISIBLE (3655 2055);
FORCEPROP 2 LAST CDS_LIB mstr_standard
J 0
(3700 2150);
PAINT ORANGE (3700 2150);
DISPLAY INVISIBLE (3700 2150);
FORCEPROP 2 LAST PATH I95
J 0
(3875 2225);
DISPLAY 1.021277 (3875 2225);
PAINT ORANGE (3875 2225);
DISPLAY INVISIBLE (3875 2225);
FORCEADD OFFPAGE..2
(3700 2100);
FORCEPROP 2 LAST $XR0 108 
J 0
(3889 2100);
DISPLAY 0.638298 (3889 2100);
PAINT MONO (3889 2100);
FORCEPROP 1 LAST COMMENT_BODY TRUE
J 0
(3655 2005);
DISPLAY 0.872340 (3655 2005);
PAINT PEACH (3655 2005);
DISPLAY INVISIBLE (3655 2005);
FORCEPROP 1 LAST OFFPAGE TRUE
J 0
(4025 1975);
DISPLAY 0.872340 (4025 1975);
PAINT GREEN (4025 1975);
DISPLAY INVISIBLE (4025 1975);
FORCEPROP 2 LAST CDS_LIB mstr_standard
J 0
(3700 2100);
PAINT ORANGE (3700 2100);
DISPLAY INVISIBLE (3700 2100);
FORCEPROP 2 LAST PATH I96
J 0
(3875 2175);
DISPLAY 1.021277 (3875 2175);
PAINT ORANGE (3875 2175);
DISPLAY INVISIBLE (3875 2175);
FORCEADD DNS..2
(-1170 2795);
PAINT RED (-1170 2795);
FORCEPROP 1 LAST COMMENT_BODY TRUE
R 1
J 0
(-1095 2570);
DISPLAY 0.872340 (-1095 2570);
PAINT GREEN (-1095 2570);
DISPLAY INVISIBLE (-1095 2570);
FORCEPROP 2 LAST CDS_LIB mstr_misc
J 0
(-1170 2795);
PAINT ORANGE (-1170 2795);
DISPLAY INVISIBLE (-1170 2795);
FORCEADD DNS..2
(-1620 2845);
PAINT RED (-1620 2845);
FORCEPROP 1 LAST COMMENT_BODY TRUE
R 1
J 0
(-1545 2620);
DISPLAY 0.872340 (-1545 2620);
PAINT GREEN (-1545 2620);
DISPLAY INVISIBLE (-1545 2620);
FORCEPROP 2 LAST CDS_LIB mstr_misc
J 0
(-1620 2845);
PAINT ORANGE (-1620 2845);
DISPLAY INVISIBLE (-1620 2845);
FORCEADD CAD_NOTE..1
(-2875 3200);
FORCEPROP 0 LAST L1 PLACE BIAS RESISTOR WITHIN 1 INCH OF PCH
J 0
(-3025 3100);
DISPLAY 0.808511 (-3025 3100);
PAINT WHITE (-3025 3100);
FORCEPROP 1 LAST COMMENT_BODY TRUE
J 0
(-2850 3300);
DISPLAY 0.978723 (-2850 3300);
PAINT PEACH (-2850 3300);
DISPLAY INVISIBLE (-2850 3300);
FORCEPROP 2 LAST CDS_LIB mstr_symbols
J 0
(-2875 3200);
PAINT ORANGE (-2875 3200);
DISPLAY INVISIBLE (-2875 3200);
FORCEADD DESIGN_NOTE..1
(-2675 325);
FORCEPROP 0 LAST L1 * NC RECOMMENDED COMPONENTS
J 0
(-2875 200);
DISPLAY 0.617021 (-2875 200);
PAINT WHITE (-2875 200);
FORCEPROP 0 LAST L2 AND VALUE.
J 0
(-2800 150);
DISPLAY 0.617021 (-2800 150);
PAINT WHITE (-2800 150);
FORCEPROP 0 LAST L3 * CAP VALUE MAY NEED TUNING.
J 0
(-2875 75);
DISPLAY 0.617021 (-2875 75);
PAINT WHITE (-2875 75);
FORCEPROP 2 LAST ROOM BMC
J 0
(-2875 275);
PAINT WHITE (-2875 275);
DISPLAY INVISIBLE (-2875 275);
FORCEPROP 1 LAST COMMENT_BODY TRUE
J 0
(-2650 425);
DISPLAY 1.319149 (-2650 425);
PAINT PEACH (-2650 425);
DISPLAY INVISIBLE (-2650 425);
FORCEPROP 2 LAST CDS_LIB mstr_symbols
J 0
(-2675 325);
PAINT MONO (-2675 325);
DISPLAY INVISIBLE (-2675 325);
FORCEPROP 2 LAST BOM_COST SM_CONTROLLER
J 0
(-2875 275);
PAINT WHITE (-2875 275);
DISPLAY INVISIBLE (-2875 275);
FORCEADD DNS..2
(2905 1095);
PAINT RED (2905 1095);
FORCEPROP 1 LAST COMMENT_BODY TRUE
R 1
J 0
(2980 870);
DISPLAY 0.872340 (2980 870);
PAINT GREEN (2980 870);
DISPLAY INVISIBLE (2980 870);
FORCEPROP 2 LAST CDS_LIB mstr_misc
J 0
(2905 1095);
PAINT ORANGE (2905 1095);
DISPLAY INVISIBLE (2905 1095);
FORCEADD CAD_NOTE..1
(-1375 -625);
FORCEPROP 0 LAST L1 PLACE ON TOP LAYER ONLY
J 0
(-1525 -750);
DISPLAY 0.936170 (-1525 -750);
PAINT WHITE (-1525 -750);
FORCEPROP 2 LAST CDS_LIB mstr_symbols
J 0
(-1375 -625);
PAINT ORANGE (-1375 -625);
DISPLAY INVISIBLE (-1375 -625);
FORCEPROP 1 LAST COMMENT_BODY TRUE
J 0
(-1350 -525);
DISPLAY 1.595745 (-1350 -525);
PAINT PEACH (-1350 -525);
DISPLAY INVISIBLE (-1350 -525);
FORCEADD DESIGN_NOTE..1
(-1125 325);
FORCEPROP 0 LAST L1 MANTAIN 0603 PACKAGE FOR
J 0
(-1325 200);
DISPLAY 0.617021 (-1325 200);
PAINT WHITE (-1325 200);
FORCEPROP 0 LAST L2 200 KOHM AND 10 MOHM RESISTORS.
J 0
(-1325 150);
DISPLAY 0.617021 (-1325 150);
PAINT WHITE (-1325 150);
FORCEPROP 2 LAST BOM_COST SM_CONTROLLER
J 0
(-1325 275);
PAINT WHITE (-1325 275);
DISPLAY INVISIBLE (-1325 275);
FORCEPROP 2 LAST ROOM BMC
J 0
(-1325 275);
PAINT WHITE (-1325 275);
DISPLAY INVISIBLE (-1325 275);
FORCEPROP 2 LAST CDS_LIB mstr_symbols
J 0
(-1125 325);
PAINT WHITE (-1125 325);
DISPLAY INVISIBLE (-1125 325);
FORCEPROP 1 LAST COMMENT_BODY TRUE
J 0
(-1100 425);
DISPLAY 1.319149 (-1100 425);
PAINT PEACH (-1100 425);
DISPLAY INVISIBLE (-1100 425);
FORCEADD DESIGN_NOTE..1
(525 475);
FORCEPROP 0 LAST L1 * NC RECOMMENDED COMPONENTS
J 0
(325 350);
DISPLAY 0.617021 (325 350);
PAINT WHITE (325 350);
FORCEPROP 0 LAST L2 AND VALUE.
J 0
(400 300);
DISPLAY 0.617021 (400 300);
PAINT WHITE (400 300);
FORCEPROP 0 LAST L3 * CAP VALUE MAY NEED TUNING.
J 0
(325 225);
DISPLAY 0.617021 (325 225);
PAINT WHITE (325 225);
FORCEPROP 2 LAST ROOM BMC
J 0
(325 425);
PAINT WHITE (325 425);
DISPLAY INVISIBLE (325 425);
FORCEPROP 2 LAST BOM_COST SM_CONTROLLER
J 0
(325 425);
PAINT WHITE (325 425);
DISPLAY INVISIBLE (325 425);
FORCEPROP 1 LAST COMMENT_BODY TRUE
J 0
(550 575);
DISPLAY 1.319149 (550 575);
PAINT PEACH (550 575);
DISPLAY INVISIBLE (550 575);
FORCEPROP 2 LAST CDS_LIB mstr_symbols
J 0
(525 475);
PAINT WHITE (525 475);
DISPLAY INVISIBLE (525 475);
FORCEADD INTEL_CORP_BPAGE..1
(4775 -1050);
FORCEPROP 1 LAST CDS_CON_LAST_MODIFIED Tue Dec 01 11:51:56 2015
J 0
(3350 -725);
PAINT ORANGE (3350 -725);
DISPLAY INVISIBLE (3350 -725);
FORCEPROP 1 LAST CUSTOM_TXT_CDS <CURRENT_DESIGN_SHEET> OF <TOTAL_DESIGN_SHEETS>
J 0
(4275 -1025);
PAINT GREEN (4275 -1025);
FORCEPROP 1 LAST CUSTOM_TXT_CDS <CON_LAST_MODIFIED>
J 0
(2850 -700);
PAINT GREEN (2850 -700);
FORCEPROP 2 LAST CUSTOM_TXT_CDS <XR_PAGE_TITLE>
J 0
(-3115 4200);
DISPLAY 0.638298 (-3115 4200);
PAINT PINK (-3115 4200);
DISPLAY INVISIBLE (-3115 4200);
FORCEPROP 1 LAST SCH_TITLE LEWISBURG 1/11 CLOCKS
J 0
(-3175 -1000);
DISPLAY 1.212766 (-3175 -1000);
PAINT YELLOW (-3175 -1000);
FORCEPROP 1 LAST SCH_ADDRESS1 2200 Mission College Blvd.
J 0
(800 -925);
DISPLAY 0.617021 (800 -925);
PAINT YELLOW (800 -925);
FORCEPROP 1 LAST SCH_ADDRESS2 P.O. BOX 58119
J 0
(800 -975);
DISPLAY 0.617021 (800 -975);
PAINT YELLOW (800 -975);
FORCEPROP 1 LAST SCH_ADDRESS3 Santa Clara, CA 95052-8119
J 0
(800 -1025);
DISPLAY 0.617021 (800 -1025);
PAINT YELLOW (800 -1025);
FORCEPROP 1 LAST SCH_NUMBER H4694802
J 0
(3475 -900);
DISPLAY 1.212766 (3475 -900);
PAINT YELLOW (3475 -900);
FORCEPROP 1 LAST SCH_DEPT BESD
J 1
(325 -950);
DISPLAY 1.212766 (325 -950);
PAINT YELLOW (325 -950);
FORCEPROP 1 LAST SCH_REV 2.420
J 0
(4525 -900);
DISPLAY 0.978723 (4525 -900);
PAINT YELLOW (4525 -900);
FORCEPROP 2 LAST PAGE_BORDER TRUE
J 0
(-3115 4200);
DISPLAY 0.638298 (-3115 4200);
PAINT PINK (-3115 4200);
DISPLAY INVISIBLE (-3115 4200);
FORCEPROP 1 LAST COMMENT_BODY TRUE
J 0
(4787 -1038);
DISPLAY 0.468085 (4787 -1038);
PAINT PEACH (4787 -1038);
DISPLAY INVISIBLE (4787 -1038);
FORCEPROP 2 LAST CDS_LIB mstr_symbols
J 0
(4775 -1050);
PAINT ORANGE (4775 -1050);
DISPLAY INVISIBLE (4775 -1050);
FORCEPROP 2 LAST CDS_XR_PAGE_TITLE CR-114 : @BASEBOARD_FAB2_LIB.BASEBOARD_FAB2(SCH_1):PAGE114
J 0
(-3115 4200);
DISPLAY 0.638298 (-3115 4200);
PAINT PINK (-3115 4200);
DISPLAY INVISIBLE (-3115 4200);
WIRE 16 -1 (2900 900)(2900 1000);
WIRE 16 -1 (-2950 2650)(-2950 2550);
WIRE 16 -1 (-1525 -475)(-1525 -325);
WIRE 16 -1 (-1525 -475)(-2025 -475);
WIRE 16 -1 (-2025 -325)(-2025 -475);
WIRE 16 -1 (-2025 -525)(-2025 -475);
WIRE 16 -1 (225 -325)(225 -475);
WIRE 16 -1 (225 -475)(-275 -475);
WIRE 16 -1 (-275 -325)(-275 -475);
WIRE 16 -1 (-275 -525)(-275 -475);
WIRE 16 -1 (3650 2850)(1525 2850);
FORCEPROP 0 LAST SIG_NAME CLK_100M_SRC13_DP
J 0
(3020 2860);
DISPLAY 0.617021 (3020 2860);
PAINT ORANGE (3020 2860);
WIRE 16 -1 (3650 2800)(1525 2800);
FORCEPROP 0 LAST SIG_NAME CLK_100M_SRC13_DN
J 0
(3020 2810);
DISPLAY 0.617021 (3020 2810);
PAINT ORANGE (3020 2810);
WIRE 16 -1 (3650 2650)(1525 2650);
FORCEPROP 0 LAST SIG_NAME CLK_100M_MEZZ4_DP
J 0
(3020 2660);
DISPLAY 0.617021 (3020 2660);
PAINT ORANGE (3020 2660);
WIRE 16 -1 (3650 2600)(1525 2600);
FORCEPROP 0 LAST SIG_NAME CLK_100M_MEZZ4_DN
J 0
(3020 2610);
DISPLAY 0.617021 (3020 2610);
PAINT ORANGE (3020 2610);
WIRE 16 -1 (3650 2550)(1525 2550);
FORCEPROP 0 LAST SIG_NAME CLK_100M_MEZZ3_DP
J 0
(3020 2560);
DISPLAY 0.617021 (3020 2560);
PAINT ORANGE (3020 2560);
WIRE 16 -1 (1525 1400)(3650 1400);
FORCEPROP 2 LAST SIG_NAME TP_CLK_24M_PMSYNC2
J 0
(3015 1410);
DISPLAY 0.617021 (3015 1410);
PAINT ORANGE (3015 1410);
FORCEPROP 2 LASTPROP $XRERR UNIQUE?
J 0
(3680 1400);
DISPLAY 0.638298 (3680 1400);
PAINT MONO (3680 1400);
DISPLAY INVISIBLE (3680 1400);
WIRE 16 -1 (3650 1500)(1525 1500);
FORCEPROP 0 LAST SIG_NAME CLK_100M_AIRMAX8_PE1_DN
J 0
(3020 1510);
DISPLAY 0.617021 (3020 1510);
PAINT ORANGE (3020 1510);
WIRE 16 -1 (3650 1600)(1525 1600);
FORCEPROP 0 LAST SIG_NAME CLK_100M_DB1200_DN
J 0
(3020 1610);
DISPLAY 0.617021 (3020 1610);
PAINT ORANGE (3020 1610);
WIRE 16 -1 (3650 1850)(1525 1850);
FORCEPROP 0 LAST SIG_NAME CLK_100M_PCH_SLOTX24_S1_DP
J 0
(3020 1860);
DISPLAY 0.617021 (3020 1860);
PAINT ORANGE (3020 1860);
WIRE 16 -1 (3650 2000)(1525 2000);
FORCEPROP 0 LAST SIG_NAME CLK_100M_PCH_SLOTX24_S3_DN
J 0
(3020 2010);
DISPLAY 0.617021 (3020 2010);
PAINT ORANGE (3020 2010);
WIRE 16 -1 (3650 2050)(1525 2050);
FORCEPROP 0 LAST SIG_NAME CLK_100M_PCH_SLOTX24_S3_DP
J 0
(3020 2060);
DISPLAY 0.617021 (3020 2060);
PAINT ORANGE (3020 2060);
WIRE 16 -1 (3650 2100)(1525 2100);
FORCEPROP 0 LAST SIG_NAME CLK_100M_PCH_SLOTX24_S4_DN
J 0
(3020 2110);
DISPLAY 0.617021 (3020 2110);
PAINT ORANGE (3020 2110);
WIRE 16 -1 (3650 1950)(1525 1950);
FORCEPROP 0 LAST SIG_NAME CLK_100M_PCH_SLOTX24_S2_DP
J 0
(3020 1960);
DISPLAY 0.617021 (3020 1960);
PAINT ORANGE (3020 1960);
WIRE 16 -1 (1850 1300)(1525 1300);
WIRE 16 -1 (1850 1300)(1850 550);
WIRE 16 -1 (3650 550)(1850 550);
WIRE 16 -1 (3650 2700)(1525 2700);
FORCEPROP 0 LAST SIG_NAME CLK_100M_SRC12_DN
J 0
(3020 2710);
DISPLAY 0.617021 (3020 2710);
PAINT ORANGE (3020 2710);
WIRE 16 -1 (3650 2750)(1525 2750);
FORCEPROP 0 LAST SIG_NAME CLK_100M_SRC12_DP
J 0
(3020 2760);
DISPLAY 0.617021 (3020 2760);
PAINT ORANGE (3020 2760);
WIRE 16 -1 (1525 2900)(3650 2900);
FORCEPROP 2 LAST SIG_NAME CLK_100M_SPRV_DN
J 0
(3015 2910);
DISPLAY 0.617021 (3015 2910);
PAINT ORANGE (3015 2910);
WIRE 16 -1 (1525 2950)(3650 2950);
FORCEPROP 2 LAST SIG_NAME CLK_100M_SPRV_DP
J 0
(3015 2960);
DISPLAY 0.617021 (3015 2960);
PAINT ORANGE (3015 2960);
WIRE 16 -1 (1525 3000)(3650 3000);
FORCEPROP 0 LAST SIG_NAME CLK_100M_M2_DN
J 0
(3015 3010);
DISPLAY 0.617021 (3015 3010);
PAINT ORANGE (3015 3010);
WIRE 16 -1 (1525 3050)(3650 3050);
FORCEPROP 2 LAST SIG_NAME CLK_100M_M2_DP
J 0
(3015 3060);
DISPLAY 0.617021 (3015 3060);
PAINT ORANGE (3015 3060);
WIRE 16 -1 (3650 1350)(2900 1350);
FORCEPROP 0 LAST SIG_NAME H_PMSYNC_CLK_24M
J 0
(3215 1360);
DISPLAY 0.617021 (3215 1360);
PAINT ORANGE (3215 1360);
WIRE 16 -1 (2900 1350)(2900 1200);
WIRE 16 -1 (2900 1350)(2400 1350);
WIRE 16 -1 (3650 2200)(1525 2200);
FORCEPROP 0 LAST SIG_NAME CLK_100M_PCH_SLOTX24_S5_DN
J 0
(3020 2210);
DISPLAY 0.617021 (3020 2210);
PAINT ORANGE (3020 2210);
WIRE 16 -1 (3650 2150)(1525 2150);
FORCEPROP 0 LAST SIG_NAME CLK_100M_PCH_SLOTX24_S4_DP
J 0
(3020 2160);
DISPLAY 0.617021 (3020 2160);
PAINT ORANGE (3020 2160);
WIRE 16 -1 (3650 1900)(1525 1900);
FORCEPROP 0 LAST SIG_NAME CLK_100M_PCH_SLOTX24_S2_DN
J 0
(3020 1910);
DISPLAY 0.617021 (3020 1910);
PAINT ORANGE (3020 1910);
WIRE 16 -1 (3650 1800)(1525 1800);
FORCEPROP 0 LAST SIG_NAME CLK_100M_PCH_SLOTX24_S1_DN
J 0
(3020 1810);
DISPLAY 0.617021 (3020 1810);
PAINT ORANGE (3020 1810);
WIRE 16 -1 (-875 625)(-275 625);
FORCEPROP 2 LAST SIG_NAME XTAL_33K_RTC1
J 0
(-785 635);
DISPLAY 0.617021 (-785 635);
PAINT ORANGE (-785 635);
WIRE 16 -1 (-275 625)(-275 475);
WIRE 16 -1 (-275 475)(-125 475);
WIRE 16 -1 (-275 125)(-275 475);
WIRE 16 -1 (-275 125)(-125 125);
WIRE 16 -1 (-275 -125)(-275 125);
WIRE 16 -1 (-1525 475)(-1525 725);
FORCEPROP 2 LAST SIG_NAME XTAL_PCH_48M_OUT
J 0
(-2460 735);
DISPLAY 0.617021 (-2460 735);
PAINT ORANGE (-2460 735);
WIRE 16 -1 (-1525 125)(-1525 475);
WIRE 16 -1 (-1675 475)(-1525 475);
WIRE 16 -1 (-1525 725)(-2525 725);
WIRE 16 -1 (-1675 125)(-1525 125);
WIRE 16 -1 (-1525 -125)(-1525 125);
WIRE 16 -1 (-2025 625)(-2025 475);
WIRE 16 -1 (-2025 625)(-2525 625);
FORCEPROP 2 LAST SIG_NAME XTAL_PCH_48M_IN
J 0
(-2460 635);
DISPLAY 0.617021 (-2460 635);
PAINT ORANGE (-2460 635);
WIRE 16 -1 (-2025 475)(-1875 475);
WIRE 16 -1 (-2025 125)(-2025 475);
WIRE 16 -1 (-2025 125)(-1875 125);
WIRE 16 -1 (-2025 -125)(-2025 125);
WIRE 16 -1 (-475 1700)(-2300 1700);
FORCEPROP 0 LAST SIG_NAME XTAL_PCH_48M_IN
J 0
(-2300 1701);
DISPLAY 0.617021 (-2300 1701);
PAINT ORANGE (-2300 1701);
WIRE 16 -1 (1525 1350)(2200 1350);
FORCEPROP 2 LAST SIG_NAME H_PMSYNC_CLK_24M_R
J 0
(1665 1360);
DISPLAY 0.617021 (1665 1360);
PAINT ORANGE (1665 1360);
FORCEPROP 2 LASTPROP $XRERR UNIQUE?
J 0
(1425 1360);
DISPLAY 0.638298 (1425 1360);
PAINT MONO (1425 1360);
DISPLAY INVISIBLE (1425 1360);
WIRE 16 -1 (3650 1750)(1525 1750);
FORCEPROP 0 LAST SIG_NAME CLK_100M_PCH_SLOTX24_S0_DP
J 0
(3020 1760);
DISPLAY 0.617021 (3020 1760);
PAINT ORANGE (3020 1760);
WIRE 16 -1 (3650 1700)(1525 1700);
FORCEPROP 0 LAST SIG_NAME CLK_100M_PCH_SLOTX24_S0_DN
J 0
(3020 1710);
DISPLAY 0.617021 (3020 1710);
PAINT ORANGE (3020 1710);
WIRE 16 -1 (3650 1650)(1525 1650);
FORCEPROP 0 LAST SIG_NAME CLK_100M_DB1200_DP
J 0
(3020 1660);
DISPLAY 0.617021 (3020 1660);
PAINT ORANGE (3020 1660);
WIRE 16 -1 (3650 1550)(1525 1550);
FORCEPROP 0 LAST SIG_NAME CLK_100M_AIRMAX8_PE1_DP
J 0
(3020 1560);
DISPLAY 0.617021 (3020 1560);
PAINT ORANGE (3020 1560);
WIRE 16 -1 (3650 2300)(1525 2300);
FORCEPROP 0 LAST SIG_NAME CLK_100M_MEZZ1_DN
J 0
(3020 2310);
DISPLAY 0.617021 (3020 2310);
PAINT ORANGE (3020 2310);
WIRE 16 -1 (3650 2350)(1525 2350);
FORCEPROP 0 LAST SIG_NAME CLK_100M_MEZZ1_DP
J 0
(3020 2360);
DISPLAY 0.617021 (3020 2360);
PAINT ORANGE (3020 2360);
WIRE 16 -1 (3650 2450)(1525 2450);
FORCEPROP 0 LAST SIG_NAME CLK_100M_MEZZ2_DP
J 0
(3020 2460);
DISPLAY 0.617021 (3020 2460);
PAINT ORANGE (3020 2460);
WIRE 16 -1 (3650 2400)(1525 2400);
FORCEPROP 0 LAST SIG_NAME CLK_100M_MEZZ2_DN
J 0
(3020 2410);
DISPLAY 0.617021 (3020 2410);
PAINT ORANGE (3020 2410);
WIRE 16 -1 (3650 2500)(1525 2500);
FORCEPROP 0 LAST SIG_NAME CLK_100M_MEZZ3_DN
J 0
(3020 2510);
DISPLAY 0.617021 (3020 2510);
PAINT ORANGE (3020 2510);
WIRE 16 -1 (3650 2250)(1525 2250);
FORCEPROP 0 LAST SIG_NAME CLK_100M_PCH_SLOTX24_S5_DP
J 0
(3020 2260);
DISPLAY 0.617021 (3020 2260);
PAINT ORANGE (3020 2260);
WIRE 16 -1 (225 725)(225 475);
WIRE 16 -1 (225 725)(-875 725);
FORCEPROP 2 LAST SIG_NAME XTAL_33K_RTC2
J 0
(-785 735);
DISPLAY 0.617021 (-785 735);
PAINT ORANGE (-785 735);
WIRE 16 -1 (75 475)(225 475);
WIRE 16 -1 (225 125)(225 475);
WIRE 16 -1 (225 125)(75 125);
WIRE 16 -1 (225 -125)(225 125);
WIRE 16 -1 (-1675 3000)(-475 3000);
FORCEPROP 2 LAST SIG_NAME TP_PCH_RSVD64
J 0
(-1685 3010);
DISPLAY 0.617021 (-1685 3010);
PAINT ORANGE (-1685 3010);
FORCEPROP 2 LASTPROP $XRERR UNIQUE?
J 0
(-1915 3000);
DISPLAY 0.638298 (-1915 3000);
PAINT MONO (-1915 3000);
DISPLAY INVISIBLE (-1915 3000);
WIRE 16 -1 (-1675 3050)(-475 3050);
FORCEPROP 2 LAST SIG_NAME TP_PCH_RSVD65
J 0
(-1685 3060);
DISPLAY 0.617021 (-1685 3060);
PAINT ORANGE (-1685 3060);
FORCEPROP 2 LASTPROP $XRERR UNIQUE?
J 0
(-1915 3050);
DISPLAY 0.638298 (-1915 3050);
PAINT MONO (-1915 3050);
DISPLAY INVISIBLE (-1915 3050);
WIRE 16 -1 (-1525 2850)(-475 2850);
FORCEPROP 2 LAST SIG_NAME CLK_100M_BMC_PE_DP
J 0
(-1010 2860);
DISPLAY 0.617021 (-1010 2860);
PAINT ORANGE (-1010 2860);
FORCEPROP 2 LASTPROP $XRERR UNIQUE?
J 0
(-1250 2860);
DISPLAY 0.638298 (-1250 2860);
PAINT MONO (-1250 2860);
DISPLAY INVISIBLE (-1250 2860);
WIRE 16 -1 (-1075 2800)(-475 2800);
FORCEPROP 2 LAST SIG_NAME CLK_100M_BMC_PE_DN
J 0
(-1010 2810);
DISPLAY 0.617021 (-1010 2810);
PAINT ORANGE (-1010 2810);
FORCEPROP 2 LASTPROP $XRERR UNIQUE?
J 0
(-1250 2810);
DISPLAY 0.638298 (-1250 2810);
PAINT MONO (-1250 2810);
DISPLAY INVISIBLE (-1250 2810);
WIRE 16 -1 (-2950 2950)(-475 2950);
FORCEPROP 0 LAST SIG_NAME A_PCH_XCLK_BIASREF
J 0
(-2750 2951);
DISPLAY 0.617021 (-2750 2951);
PAINT ORANGE (-2750 2951);
FORCEPROP 2 LASTPROP $XRERR UNIQUE?
J 0
(-2990 2951);
DISPLAY 0.638298 (-2990 2951);
PAINT MONO (-2990 2951);
DISPLAY INVISIBLE (-2990 2951);
WIRE 16 -1 (-2950 2950)(-2950 2850);
WIRE 16 -1 (-475 2650)(-2300 2650);
FORCEPROP 0 LAST SIG_NAME TP_CLK_100M_PLAT1_DP
J 0
(-2300 2660);
DISPLAY 0.617021 (-2300 2660);
PAINT ORANGE (-2300 2660);
FORCEPROP 2 LASTPROP $XRERR UNIQUE?
J 0
(-2540 2650);
DISPLAY 0.638298 (-2540 2650);
PAINT MONO (-2540 2650);
DISPLAY INVISIBLE (-2540 2650);
WIRE 16 -1 (-475 2600)(-2300 2600);
FORCEPROP 0 LAST SIG_NAME TP_CLK_100M_PLAT1_DN
J 0
(-2300 2610);
DISPLAY 0.617021 (-2300 2610);
PAINT ORANGE (-2300 2610);
FORCEPROP 2 LASTPROP $XRERR UNIQUE?
J 0
(-2540 2600);
DISPLAY 0.638298 (-2540 2600);
PAINT MONO (-2540 2600);
DISPLAY INVISIBLE (-2540 2600);
WIRE 16 -1 (-2300 2550)(-475 2550);
FORCEPROP 0 LAST SIG_NAME TP_CLK_100M_NSSCC1_DP
J 0
(-2300 2560);
DISPLAY 0.617021 (-2300 2560);
PAINT ORANGE (-2300 2560);
FORCEPROP 2 LASTPROP $XRERR UNIQUE?
J 0
(-2540 2550);
DISPLAY 0.638298 (-2540 2550);
PAINT MONO (-2540 2550);
DISPLAY INVISIBLE (-2540 2550);
WIRE 16 -1 (-2300 2500)(-475 2500);
FORCEPROP 0 LAST SIG_NAME TP_CLK_100M_NSSCC1_DN
J 0
(-2300 2510);
DISPLAY 0.617021 (-2300 2510);
PAINT ORANGE (-2300 2510);
FORCEPROP 2 LASTPROP $XRERR UNIQUE?
J 0
(-2540 2500);
DISPLAY 0.638298 (-2540 2500);
PAINT MONO (-2540 2500);
DISPLAY INVISIBLE (-2540 2500);
WIRE 16 -1 (-475 2750)(-2300 2750);
FORCEPROP 0 LAST SIG_NAME TP_CLK_100M_NSSCC0_DP
J 0
(-2300 2760);
DISPLAY 0.617021 (-2300 2760);
PAINT ORANGE (-2300 2760);
FORCEPROP 2 LASTPROP $XRERR UNIQUE?
J 0
(-2540 2750);
DISPLAY 0.638298 (-2540 2750);
PAINT MONO (-2540 2750);
DISPLAY INVISIBLE (-2540 2750);
WIRE 16 -1 (-475 2700)(-2300 2700);
FORCEPROP 0 LAST SIG_NAME TP_CLK_100M_NSSCC0_DN
J 0
(-2300 2710);
DISPLAY 0.617021 (-2300 2710);
PAINT ORANGE (-2300 2710);
FORCEPROP 2 LASTPROP $XRERR UNIQUE?
J 0
(-2540 2700);
DISPLAY 0.638298 (-2540 2700);
PAINT MONO (-2540 2700);
DISPLAY INVISIBLE (-2540 2700);
WIRE 16 -1 (-475 1900)(-2300 1900);
FORCEPROP 0 LAST SIG_NAME XTAL_33K_RTC2
J 0
(-2300 1910);
DISPLAY 0.617021 (-2300 1910);
PAINT ORANGE (-2300 1910);
WIRE 16 -1 (-475 1350)(-2300 1350);
FORCEPROP 0 LAST SIG_NAME XTAL_PCH_48M_OUT
J 0
(-2300 1351);
DISPLAY 0.617021 (-2300 1351);
PAINT ORANGE (-2300 1351);
WIRE 16 -1 (-2300 2800)(-1275 2800);
FORCEPROP 2 LAST SIG_NAME CLK_100M_BMC_PE_R_DN
J 0
(-2300 2810);
DISPLAY 0.617021 (-2300 2810);
PAINT ORANGE (-2300 2810);
WIRE 16 -1 (-2300 2850)(-1725 2850);
FORCEPROP 2 LAST SIG_NAME CLK_100M_BMC_PE_R_DP
J 0
(-2300 2860);
DISPLAY 0.617021 (-2300 2860);
PAINT ORANGE (-2300 2860);
WIRE 16 -1 (-2300 2400)(-475 2400);
FORCEPROP 0 LAST SIG_NAME CLK_100M_PCH_XDP_DN
J 0
(-2300 2401);
DISPLAY 0.617021 (-2300 2401);
PAINT ORANGE (-2300 2401);
WIRE 16 -1 (-2300 2450)(-475 2450);
FORCEPROP 0 LAST SIG_NAME CLK_100M_PCH_XDP_DP
J 0
(-2300 2451);
DISPLAY 0.617021 (-2300 2451);
PAINT ORANGE (-2300 2451);
WIRE 16 -1 (-2300 2300)(-475 2300);
FORCEPROP 0 LAST SIG_NAME XTAL_33K_RTC1
J 0
(-2300 2310);
DISPLAY 0.617021 (-2300 2310);
PAINT ORANGE (-2300 2310);
DOT 1 (2900 1350);
DOT 1 (225 125);
DOT 1 (-275 125);
DOT 1 (-1525 125);
DOT 1 (-1525 475);
DOT 1 (-2025 475);
DOT 1 (-2025 125);
DOT 1 (-275 -475);
DOT 1 (-2025 -475);
DOT 1 (-275 475);
DOT 1 (225 475);
FORCENOTE
ROOM=SB
(-3000 -750) 0;
DISPLAY LEFT (-3000 -750);
DISPLAY 0.808511 (-3000 -750);
PAINT PURPLE (-3000 -750);
QUIT
